FILE_TYPE = MACRO_DRAWING;
SET COLOR_WIRE YELLOW;
SET COLOR_PROP MONO;
SET COLOR_DOT WHITE;
SET COLOR_ARC YELLOW;
SET COLOR_BODY GREEN;
SET COLOR_NOTE MONO;
SET PROP_DISPLAY VALUE;
SET PAGE_NUMBER P183;
FORCEADD PI7C9X1172..1
(1475 1025);
FORCEPROP 2 LASTPIN (825 325) $PN 10
J 2
(815 335);
DISPLAY 0.617021 (815 335);
PAINT MONO (815 335);
FORCEPROP 2 LASTPIN (825 725) $PN 17
J 2
(815 735);
DISPLAY 0.617021 (815 735);
PAINT MONO (815 735);
FORCEPROP 2 LASTPIN (825 975) $PN 24
J 2
(815 985);
DISPLAY 0.617021 (815 985);
PAINT MONO (815 985);
FORCEPROP 2 LASTPIN (825 825) $PN 31
J 2
(815 835);
DISPLAY 0.617021 (815 835);
PAINT MONO (815 835);
FORCEPROP 2 LASTPIN (825 875) $PN 30
J 2
(815 885);
DISPLAY 0.617021 (815 885);
PAINT MONO (815 885);
FORCEPROP 2 LASTPIN (825 575) $PN 9
J 2
(815 585);
DISPLAY 0.617021 (815 585);
PAINT MONO (815 585);
FORCEPROP 2 LASTPIN (825 675) $PN 3
J 2
(815 685);
DISPLAY 0.617021 (815 685);
PAINT MONO (815 685);
FORCEPROP 2 LASTPIN (825 1025) $PN 32
J 2
(815 1035);
DISPLAY 0.617021 (815 1035);
PAINT MONO (815 1035);
FORCEPROP 2 LASTPIN (825 1075) $PN 18
J 2
(815 1085);
DISPLAY 0.617021 (815 1085);
PAINT MONO (815 1085);
FORCEPROP 2 LASTPIN (825 1125) $PN 19
J 2
(815 1135);
DISPLAY 0.617021 (815 1135);
PAINT MONO (815 1135);
FORCEPROP 2 LASTPIN (825 1425) $PN 16
J 2
(815 1435);
DISPLAY 0.617021 (815 1435);
PAINT MONO (815 1435);
FORCEPROP 2 LASTPIN (825 1475) $PN 25
J 2
(815 1485);
DISPLAY 0.617021 (815 1485);
PAINT MONO (815 1485);
FORCEPROP 2 LASTPIN (825 1225) $PN 4
J 2
(815 1235);
DISPLAY 0.617021 (815 1235);
PAINT MONO (815 1235);
FORCEPROP 2 LASTPIN (825 1275) $PN 5
J 2
(815 1285);
DISPLAY 0.617021 (815 1285);
PAINT MONO (815 1285);
FORCEPROP 2 LASTPIN (825 1625) $PN 29
J 2
(815 1635);
DISPLAY 0.617021 (815 1635);
PAINT MONO (815 1635);
FORCEPROP 1 LAST LOCATION EU9F3
J 0
(875 1875);
DISPLAY 0.617021 (875 1875);
PAINT AQUA (875 1875);
FORCEPROP 1 LAST MATERIAL IC
J 0
(875 1825);
DISPLAY 0.617021 (875 1825);
PAINT SKYBLUE (875 1825);
FORCEPROP 1 LAST PART_NUMBER H66899-001
J 0
(875 225);
DISPLAY 0.617021 (875 225);
PAINT BLUE (875 225);
FORCEPROP 2 LASTPIN (2125 375) $PN 12
J 0
(2135 385);
DISPLAY 0.617021 (2135 385);
PAINT MONO (2135 385);
FORCEPROP 2 LASTPIN (2125 325) $PN 33
J 0
(2135 335);
DISPLAY 0.617021 (2135 335);
PAINT MONO (2135 335);
FORCEPROP 2 LASTPIN (2125 675) $PN 2
J 0
(2135 685);
DISPLAY 0.617021 (2135 685);
PAINT MONO (2135 685);
FORCEPROP 2 LASTPIN (2125 525) $PN 20
J 0
(2135 535);
DISPLAY 0.617021 (2135 535);
PAINT MONO (2135 535);
FORCEPROP 2 LASTPIN (2125 775) $PN 13
J 0
(2135 785);
DISPLAY 0.617021 (2135 785);
PAINT MONO (2135 785);
FORCEPROP 2 LASTPIN (2125 825) $PN 23
J 0
(2135 835);
DISPLAY 0.617021 (2135 835);
PAINT MONO (2135 835);
FORCEPROP 2 LASTPIN (2125 875) $PN 11
J 0
(2135 885);
DISPLAY 0.617021 (2135 885);
PAINT MONO (2135 885);
FORCEPROP 2 LASTPIN (2125 925) $PN 14
J 0
(2135 935);
DISPLAY 0.617021 (2135 935);
PAINT MONO (2135 935);
FORCEPROP 2 LASTPIN (2125 975) $PN 26
J 0
(2135 985);
DISPLAY 0.617021 (2135 985);
PAINT MONO (2135 985);
FORCEPROP 2 LASTPIN (2125 1225) $PN 7
J 0
(2135 1235);
DISPLAY 0.617021 (2135 1235);
PAINT MONO (2135 1235);
FORCEPROP 2 LASTPIN (2125 1025) $PN 22
J 0
(2135 1035);
DISPLAY 0.617021 (2135 1035);
PAINT MONO (2135 1035);
FORCEPROP 2 LASTPIN (2125 1075) $PN 27
J 0
(2135 1085);
DISPLAY 0.617021 (2135 1085);
PAINT MONO (2135 1085);
FORCEPROP 2 LASTPIN (2125 1125) $PN 28
J 0
(2135 1135);
DISPLAY 0.617021 (2135 1135);
PAINT MONO (2135 1135);
FORCEPROP 2 LASTPIN (2125 1275) $PN 6
J 0
(2135 1285);
DISPLAY 0.617021 (2135 1285);
PAINT MONO (2135 1285);
FORCEPROP 2 LASTPIN (2125 1425) $PN 15
J 0
(2135 1435);
DISPLAY 0.617021 (2135 1435);
PAINT MONO (2135 1435);
FORCEPROP 2 LASTPIN (2125 1475) $PN 21
J 0
(2135 1485);
DISPLAY 0.617021 (2135 1485);
PAINT MONO (2135 1485);
FORCEPROP 2 LASTPIN (2125 1625) $PN 8
J 0
(2135 1635);
DISPLAY 0.617021 (2135 1635);
PAINT MONO (2135 1635);
FORCEPROP 2 LASTPIN (2125 1575) $PN 1
J 0
(2135 1585);
DISPLAY 0.617021 (2135 1585);
PAINT MONO (2135 1585);
FORCEPROP 1 LAST PACK_TYPE QFN
J 0
(875 1925);
PAINT SKYBLUE (875 1925);
DISPLAY INVISIBLE (875 1925);
FORCEPROP 2 LAST ROOM LBG
J 0
(875 1925);
DISPLAY 1.021277 (875 1925);
PAINT ORANGE (875 1925);
DISPLAY INVISIBLE (875 1925);
FORCEPROP 2 LAST CDS_LOCATION EU9F3
J 0
(875 1875);
DISPLAY 0.617021 (875 1875);
PAINT AQUA (875 1875);
DISPLAY INVISIBLE (875 1875);
FORCEPROP 2 LAST $SEC 1
J 0
(875 1925);
PAINT MONO (875 1925);
DISPLAY INVISIBLE (875 1925);
FORCEPROP 2 LAST CDS_SEC 1
J 0
(875 1925);
PAINT MONO (875 1925);
DISPLAY INVISIBLE (875 1925);
FORCEPROP 2 LAST BOM_COST LBG_UART
J 0
(875 1975);
DISPLAY 1.021277 (875 1975);
PAINT ORANGE (875 1975);
DISPLAY INVISIBLE (875 1975);
FORCEPROP 2 LAST CDS_LIB mstr_controller
J 0
(1475 1025);
PAINT MONO (1475 1025);
DISPLAY INVISIBLE (1475 1025);
FORCEPROP 1 LAST PATH I1
J 0
(1625 1825);
PAINT GREEN (1625 1825);
DISPLAY INVISIBLE (1625 1825);
FORCEADD GND..1
(2250 25);
FORCEPROP 3 LASTPIN (2250 75) SIG_NAME GND\g
J 0
(2260 85);
DISPLAY 0.659574 (2260 85);
PAINT MONO (2260 85);
DISPLAY INVISIBLE (2260 85);
FORCEPROP 1 LAST BODY_TYPE PLUMBING
J 0
(2205 -18);
DISPLAY 0.340426 (2205 -18);
PAINT GREEN (2205 -18);
DISPLAY INVISIBLE (2205 -18);
FORCEPROP 1 LAST VOLTAGE 0.0V
J 0
(2205 -18);
DISPLAY 0.340426 (2205 -18);
PAINT SKYBLUE (2205 -18);
DISPLAY INVISIBLE (2205 -18);
FORCEPROP 1 LAST SIZE 1B
J 0
(2325 -25);
DISPLAY 0.872340 (2325 -25);
PAINT AQUA (2325 -25);
DISPLAY INVISIBLE (2325 -25);
FORCEPROP 2 LAST CDS_LIB mstr_symbols
J 0
(2250 25);
PAINT MONO (2250 25);
DISPLAY INVISIBLE (2250 25);
FORCEPROP 1 LAST HDL_POWER GND
J 0
(2250 175);
DISPLAY 0.872340 (2250 175);
PAINT GREEN (2250 175);
DISPLAY INVISIBLE (2250 175);
FORCEPROP 1 LAST PATH I10
J 0
(2325 25);
DISPLAY 0.872340 (2325 25);
PAINT AQUA (2325 25);
DISPLAY INVISIBLE (2325 25);
FORCEADD RES..2
(-1150 600);
FORCEPROP 1 LAST TOLERANCE 1%
J 0
(-1105 625);
DISPLAY 0.617021 (-1105 625);
PAINT SKYBLUE (-1105 625);
FORCEPROP 1 LAST WATTAGE 1/16W
J 0
(-1110 575);
DISPLAY 0.617021 (-1110 575);
PAINT SKYBLUE (-1110 575);
FORCEPROP 1 LAST MATERIAL CHIP
J 0
(-1110 525);
DISPLAY 0.617021 (-1110 525);
PAINT SKYBLUE (-1110 525);
FORCEPROP 1 LAST PACK_TYPE 0402
J 0
(-1110 425);
DISPLAY 0.617021 (-1110 425);
PAINT SKYBLUE (-1110 425);
FORCEPROP 1 LAST VALUE 1.00K
J 0
(-1105 675);
DISPLAY 0.617021 (-1105 675);
PAINT SKYBLUE (-1105 675);
FORCEPROP 1 LAST PART_NUMBER G21796-026
J 0
(-1110 475);
DISPLAY 0.617021 (-1110 475);
PAINT BLUE (-1110 475);
FORCEPROP 1 LAST LOCATION R9F50
J 0
(-1105 725);
DISPLAY 0.617021 (-1105 725);
PAINT AQUA (-1105 725);
FORCEPROP 1 LASTPIN (-1150 500) $PN 2
J 0
(-1145 510);
DISPLAY 0.787234 (-1145 510);
PAINT ORANGE (-1145 510);
DISPLAY INVISIBLE (-1145 510);
FORCEPROP 2 LAST CDS_LIB mstr_discrete
J 0
(-1150 600);
PAINT ORANGE (-1150 600);
DISPLAY INVISIBLE (-1150 600);
FORCEPROP 2 LAST CDS_LOCATION R9F50
J 0
(-1105 725);
DISPLAY 0.617021 (-1105 725);
PAINT AQUA (-1105 725);
DISPLAY INVISIBLE (-1105 725);
FORCEPROP 1 LASTPIN (-1150 700) $PN 1
J 0
(-1145 662);
DISPLAY 0.787234 (-1145 662);
PAINT ORANGE (-1145 662);
DISPLAY INVISIBLE (-1145 662);
FORCEPROP 2 LAST BOM_COST LBG_UART
J 0
(-1100 825);
DISPLAY 1.021277 (-1100 825);
PAINT ORANGE (-1100 825);
DISPLAY INVISIBLE (-1100 825);
FORCEPROP 2 LAST CDS_SEC 1
J 0
(-1100 825);
PAINT MONO (-1100 825);
DISPLAY INVISIBLE (-1100 825);
FORCEPROP 2 LAST $SEC 1
J 0
(-1100 825);
PAINT MONO (-1100 825);
DISPLAY INVISIBLE (-1100 825);
FORCEPROP 1 LAST PATH I11
J 0
(-1100 775);
DISPLAY 0.978723 (-1100 775);
PAINT WHITE (-1100 775);
DISPLAY INVISIBLE (-1100 775);
FORCEPROP 2 LAST ROOM LBG
J 0
(-1100 775);
DISPLAY 1.021277 (-1100 775);
PAINT ORANGE (-1100 775);
DISPLAY INVISIBLE (-1100 775);
FORCEADD RES..2
(-1500 600);
FORCEPROP 1 LAST PACK_TYPE 0402
J 0
(-1460 425);
DISPLAY 0.617021 (-1460 425);
PAINT SKYBLUE (-1460 425);
FORCEPROP 1 LAST PART_NUMBER G21796-026
J 0
(-1460 475);
DISPLAY 0.617021 (-1460 475);
PAINT BLUE (-1460 475);
FORCEPROP 1 LAST WATTAGE 1/16W
J 0
(-1460 575);
DISPLAY 0.617021 (-1460 575);
PAINT SKYBLUE (-1460 575);
FORCEPROP 1 LAST LOCATION R9F51
J 0
(-1455 725);
DISPLAY 0.617021 (-1455 725);
PAINT AQUA (-1455 725);
FORCEPROP 1 LAST VALUE 1.00K
J 0
(-1455 675);
DISPLAY 0.617021 (-1455 675);
PAINT SKYBLUE (-1455 675);
FORCEPROP 1 LAST TOLERANCE 1%
J 0
(-1455 625);
DISPLAY 0.617021 (-1455 625);
PAINT SKYBLUE (-1455 625);
FORCEPROP 1 LAST MATERIAL CHIP
J 0
(-1460 525);
DISPLAY 0.617021 (-1460 525);
PAINT SKYBLUE (-1460 525);
FORCEPROP 1 LASTPIN (-1500 500) $PN 2
J 0
(-1495 510);
DISPLAY 0.787234 (-1495 510);
PAINT ORANGE (-1495 510);
DISPLAY INVISIBLE (-1495 510);
FORCEPROP 1 LASTPIN (-1500 700) $PN 1
J 0
(-1495 662);
DISPLAY 0.787234 (-1495 662);
PAINT ORANGE (-1495 662);
DISPLAY INVISIBLE (-1495 662);
FORCEPROP 2 LAST CDS_LOCATION R9F51
J 0
(-1455 725);
DISPLAY 0.617021 (-1455 725);
PAINT AQUA (-1455 725);
DISPLAY INVISIBLE (-1455 725);
FORCEPROP 2 LAST CDS_LIB mstr_discrete
J 0
(-1500 600);
PAINT ORANGE (-1500 600);
DISPLAY INVISIBLE (-1500 600);
FORCEPROP 2 LAST BOM_COST LBG_UART
J 0
(-1450 825);
DISPLAY 1.021277 (-1450 825);
PAINT ORANGE (-1450 825);
DISPLAY INVISIBLE (-1450 825);
FORCEPROP 2 LAST CDS_SEC 1
J 0
(-1450 825);
PAINT MONO (-1450 825);
DISPLAY INVISIBLE (-1450 825);
FORCEPROP 2 LAST $SEC 1
J 0
(-1450 825);
PAINT MONO (-1450 825);
DISPLAY INVISIBLE (-1450 825);
FORCEPROP 1 LAST PATH I12
J 0
(-1450 775);
DISPLAY 0.978723 (-1450 775);
PAINT WHITE (-1450 775);
DISPLAY INVISIBLE (-1450 775);
FORCEPROP 2 LAST ROOM LBG
J 0
(-1450 775);
DISPLAY 1.021277 (-1450 775);
PAINT ORANGE (-1450 775);
DISPLAY INVISIBLE (-1450 775);
FORCEADD RES..2
(-1150 1050);
FORCEPROP 1 LASTPIN (-1150 950) $PN 2
J 0
(-1145 960);
DISPLAY 0.617021 (-1145 960);
PAINT ORANGE (-1145 960);
FORCEPROP 1 LASTPIN (-1150 1150) $PN 1
J 0
(-1145 1112);
DISPLAY 0.617021 (-1145 1112);
PAINT ORANGE (-1145 1112);
FORCEPROP 1 LAST TOLERANCE 1%
J 0
(-1105 1075);
DISPLAY 0.617021 (-1105 1075);
PAINT SKYBLUE (-1105 1075);
FORCEPROP 1 LAST WATTAGE 1/16W
J 0
(-1110 1025);
DISPLAY 0.617021 (-1110 1025);
PAINT SKYBLUE (-1110 1025);
FORCEPROP 1 LAST PACK_TYPE 0402
J 0
(-1110 875);
DISPLAY 0.617021 (-1110 875);
PAINT SKYBLUE (-1110 875);
FORCEPROP 1 LAST VALUE 4.75K
J 0
(-1105 1125);
DISPLAY 0.617021 (-1105 1125);
PAINT SKYBLUE (-1105 1125);
FORCEPROP 1 LAST PART_NUMBER G21796-072
J 0
(-1110 925);
DISPLAY 0.617021 (-1110 925);
PAINT BLUE (-1110 925);
FORCEPROP 1 LAST LOCATION R9F48
J 0
(-1105 1175);
DISPLAY 0.617021 (-1105 1175);
PAINT AQUA (-1105 1175);
FORCEPROP 1 LAST MATERIAL EMPTY
J 0
(-1110 975);
DISPLAY 0.617021 (-1110 975);
PAINT RED (-1110 975);
FORCEPROP 2 LAST CDS_LIB mstr_discrete
J 0
(-1150 1050);
PAINT MONO (-1150 1050);
DISPLAY INVISIBLE (-1150 1050);
FORCEPROP 2 LAST CDS_LOCATION R9F48
J 0
(-1105 1175);
DISPLAY 0.617021 (-1105 1175);
PAINT AQUA (-1105 1175);
DISPLAY INVISIBLE (-1105 1175);
FORCEPROP 1 LAST PATH I13
J 0
(-1100 1225);
DISPLAY 0.978723 (-1100 1225);
PAINT WHITE (-1100 1225);
DISPLAY INVISIBLE (-1100 1225);
FORCEPROP 2 LAST ROOM LBG
J 0
(-1100 1225);
DISPLAY 1.021277 (-1100 1225);
PAINT ORANGE (-1100 1225);
DISPLAY INVISIBLE (-1100 1225);
FORCEPROP 2 LAST BOM_COST LBG_UART
J 0
(-1100 1275);
DISPLAY 1.021277 (-1100 1275);
PAINT ORANGE (-1100 1275);
DISPLAY INVISIBLE (-1100 1275);
FORCEPROP 2 LAST SEC_TYPE 0402
J 0
(-1100 1275);
DISPLAY 1.021277 (-1100 1275);
PAINT ORANGE (-1100 1275);
DISPLAY INVISIBLE (-1100 1275);
FORCEPROP 2 LAST SEC 1
J 0
(-1100 1275);
PAINT MONO (-1100 1275);
DISPLAY INVISIBLE (-1100 1275);
FORCEADD RES..2
(-1500 1050);
FORCEPROP 1 LASTPIN (-1500 950) $PN 2
J 0
(-1495 960);
DISPLAY 0.617021 (-1495 960);
PAINT ORANGE (-1495 960);
FORCEPROP 1 LAST PACK_TYPE 0402
J 0
(-1460 875);
DISPLAY 0.617021 (-1460 875);
PAINT SKYBLUE (-1460 875);
FORCEPROP 1 LAST MATERIAL EMPTY
J 0
(-1460 975);
DISPLAY 0.617021 (-1460 975);
PAINT RED (-1460 975);
FORCEPROP 1 LAST PART_NUMBER G21796-072
J 0
(-1460 925);
DISPLAY 0.617021 (-1460 925);
PAINT BLUE (-1460 925);
FORCEPROP 1 LASTPIN (-1500 1150) $PN 1
J 0
(-1495 1112);
DISPLAY 0.617021 (-1495 1112);
PAINT ORANGE (-1495 1112);
FORCEPROP 1 LAST WATTAGE 1/16W
J 0
(-1460 1025);
DISPLAY 0.617021 (-1460 1025);
PAINT SKYBLUE (-1460 1025);
FORCEPROP 1 LAST TOLERANCE 1%
J 0
(-1455 1075);
DISPLAY 0.617021 (-1455 1075);
PAINT SKYBLUE (-1455 1075);
FORCEPROP 1 LAST VALUE 4.75K
J 0
(-1455 1125);
DISPLAY 0.617021 (-1455 1125);
PAINT SKYBLUE (-1455 1125);
FORCEPROP 1 LAST LOCATION R9F49
J 0
(-1455 1175);
DISPLAY 0.617021 (-1455 1175);
PAINT AQUA (-1455 1175);
FORCEPROP 2 LAST CDS_LIB mstr_discrete
J 0
(-1500 1050);
PAINT MONO (-1500 1050);
DISPLAY INVISIBLE (-1500 1050);
FORCEPROP 2 LAST CDS_LOCATION R9F49
J 0
(-1455 1175);
DISPLAY 0.617021 (-1455 1175);
PAINT AQUA (-1455 1175);
DISPLAY INVISIBLE (-1455 1175);
FORCEPROP 1 LAST PATH I14
J 0
(-1450 1225);
DISPLAY 0.978723 (-1450 1225);
PAINT WHITE (-1450 1225);
DISPLAY INVISIBLE (-1450 1225);
FORCEPROP 2 LAST ROOM LBG
J 0
(-1450 1225);
DISPLAY 1.021277 (-1450 1225);
PAINT ORANGE (-1450 1225);
DISPLAY INVISIBLE (-1450 1225);
FORCEPROP 2 LAST BOM_COST LBG_UART
J 0
(-1450 1275);
DISPLAY 1.021277 (-1450 1275);
PAINT ORANGE (-1450 1275);
DISPLAY INVISIBLE (-1450 1275);
FORCEPROP 2 LAST SEC_TYPE 0402
J 0
(-1450 1275);
DISPLAY 1.021277 (-1450 1275);
PAINT ORANGE (-1450 1275);
DISPLAY INVISIBLE (-1450 1275);
FORCEPROP 2 LAST SEC 1
J 0
(-1450 1275);
PAINT MONO (-1450 1275);
DISPLAY INVISIBLE (-1450 1275);
FORCEADD P3V3_STBY..1
(-1500 1300);
FORCEPROP 3 LASTPIN (-1500 1250) SIG_NAME P3V3_STBY\g
J 0
(-1490 1260);
DISPLAY 0.659574 (-1490 1260);
PAINT MONO (-1490 1260);
DISPLAY INVISIBLE (-1490 1260);
FORCEPROP 1 LAST HDL_POWER P3V3_STBY
J 0
(-1800 1175);
DISPLAY 0.872340 (-1800 1175);
PAINT ORANGE (-1800 1175);
DISPLAY INVISIBLE (-1800 1175);
FORCEPROP 1 LAST BODY_TYPE PLUMBING
J 0
(-1545 1257);
DISPLAY 0.340426 (-1545 1257);
PAINT GREEN (-1545 1257);
DISPLAY INVISIBLE (-1545 1257);
FORCEPROP 1 LAST VOLTAGE 3.3V
J 0
(-1545 1257);
DISPLAY 0.340426 (-1545 1257);
PAINT SKYBLUE (-1545 1257);
DISPLAY INVISIBLE (-1545 1257);
FORCEPROP 1 LAST SIZE 1B
J 0
(-1455 1322);
DISPLAY 0.340426 (-1455 1322);
PAINT GREEN (-1455 1322);
DISPLAY INVISIBLE (-1455 1322);
FORCEPROP 2 LAST CDS_LIB mstr_symbols
J 0
(-1500 1300);
PAINT MONO (-1500 1300);
DISPLAY INVISIBLE (-1500 1300);
FORCEPROP 1 LAST PATH I15
J 0
(-1455 1302);
DISPLAY 0.340426 (-1455 1302);
PAINT GREEN (-1455 1302);
DISPLAY INVISIBLE (-1455 1302);
FORCEADD P3V3_STBY..1
(-1150 1300);
FORCEPROP 3 LASTPIN (-1150 1250) SIG_NAME P3V3_STBY\g
J 0
(-1140 1260);
DISPLAY 0.659574 (-1140 1260);
PAINT MONO (-1140 1260);
DISPLAY INVISIBLE (-1140 1260);
FORCEPROP 1 LAST HDL_POWER P3V3_STBY
J 0
(-1450 1175);
DISPLAY 0.872340 (-1450 1175);
PAINT ORANGE (-1450 1175);
DISPLAY INVISIBLE (-1450 1175);
FORCEPROP 1 LAST BODY_TYPE PLUMBING
J 0
(-1195 1257);
DISPLAY 0.340426 (-1195 1257);
PAINT GREEN (-1195 1257);
DISPLAY INVISIBLE (-1195 1257);
FORCEPROP 1 LAST VOLTAGE 3.3V
J 0
(-1195 1257);
DISPLAY 0.340426 (-1195 1257);
PAINT SKYBLUE (-1195 1257);
DISPLAY INVISIBLE (-1195 1257);
FORCEPROP 1 LAST SIZE 1B
J 0
(-1105 1322);
DISPLAY 0.340426 (-1105 1322);
PAINT GREEN (-1105 1322);
DISPLAY INVISIBLE (-1105 1322);
FORCEPROP 2 LAST CDS_LIB mstr_symbols
J 0
(-1150 1300);
PAINT MONO (-1150 1300);
DISPLAY INVISIBLE (-1150 1300);
FORCEPROP 1 LAST PATH I16
J 0
(-1105 1302);
DISPLAY 0.340426 (-1105 1302);
PAINT GREEN (-1105 1302);
DISPLAY INVISIBLE (-1105 1302);
FORCEADD GND..1
(-1500 325);
FORCEPROP 3 LASTPIN (-1500 375) SIG_NAME GND\g
J 0
(-1490 385);
DISPLAY 0.659574 (-1490 385);
PAINT MONO (-1490 385);
DISPLAY INVISIBLE (-1490 385);
FORCEPROP 1 LAST BODY_TYPE PLUMBING
J 0
(-1545 282);
DISPLAY 0.340426 (-1545 282);
PAINT GREEN (-1545 282);
DISPLAY INVISIBLE (-1545 282);
FORCEPROP 1 LAST VOLTAGE 0.0V
J 0
(-1545 282);
DISPLAY 0.340426 (-1545 282);
PAINT SKYBLUE (-1545 282);
DISPLAY INVISIBLE (-1545 282);
FORCEPROP 2 LAST CDS_LIB mstr_symbols
J 0
(-1500 325);
PAINT MONO (-1500 325);
DISPLAY INVISIBLE (-1500 325);
FORCEPROP 1 LAST SIZE 1B
J 0
(-1425 275);
DISPLAY 0.872340 (-1425 275);
PAINT AQUA (-1425 275);
DISPLAY INVISIBLE (-1425 275);
FORCEPROP 1 LAST PATH I17
J 0
(-1425 325);
DISPLAY 0.872340 (-1425 325);
PAINT AQUA (-1425 325);
DISPLAY INVISIBLE (-1425 325);
FORCEPROP 1 LAST HDL_POWER GND
J 0
(-1500 475);
DISPLAY 0.872340 (-1500 475);
PAINT GREEN (-1500 475);
DISPLAY INVISIBLE (-1500 475);
FORCEADD GND..1
(-1150 325);
FORCEPROP 3 LASTPIN (-1150 375) SIG_NAME GND\g
J 0
(-1140 385);
DISPLAY 0.659574 (-1140 385);
PAINT MONO (-1140 385);
DISPLAY INVISIBLE (-1140 385);
FORCEPROP 1 LAST BODY_TYPE PLUMBING
J 0
(-1195 282);
DISPLAY 0.340426 (-1195 282);
PAINT GREEN (-1195 282);
DISPLAY INVISIBLE (-1195 282);
FORCEPROP 1 LAST VOLTAGE 0.0V
J 0
(-1195 282);
DISPLAY 0.340426 (-1195 282);
PAINT SKYBLUE (-1195 282);
DISPLAY INVISIBLE (-1195 282);
FORCEPROP 2 LAST CDS_LIB mstr_symbols
J 0
(-1150 325);
PAINT MONO (-1150 325);
DISPLAY INVISIBLE (-1150 325);
FORCEPROP 1 LAST SIZE 1B
J 0
(-1075 275);
DISPLAY 0.872340 (-1075 275);
PAINT AQUA (-1075 275);
DISPLAY INVISIBLE (-1075 275);
FORCEPROP 1 LAST PATH I18
J 0
(-1075 325);
DISPLAY 0.872340 (-1075 325);
PAINT AQUA (-1075 325);
DISPLAY INVISIBLE (-1075 325);
FORCEPROP 1 LAST HDL_POWER GND
J 0
(-1150 475);
DISPLAY 0.872340 (-1150 475);
PAINT GREEN (-1150 475);
DISPLAY INVISIBLE (-1150 475);
FORCEADD CRYSTAL..1
(-225 50);
FORCEPROP 1 LAST MATERIAL IC
J 0
(-236 -34);
DISPLAY 0.617021 (-236 -34);
PAINT SKYBLUE (-236 -34);
FORCEPROP 1 LASTPIN (-325 50) $PN 1
J 2
(-280 60);
DISPLAY 0.617021 (-280 60);
PAINT AQUA (-280 60);
FORCEPROP 1 LAST VALUE 24.000MHZ
J 1
(-218 111);
DISPLAY 0.617021 (-218 111);
PAINT SKYBLUE (-218 111);
FORCEPROP 1 LAST LOCATION Y9F1
J 1
(-220 149);
DISPLAY 0.617021 (-220 149);
PAINT AQUA (-220 149);
FORCEPROP 1 LASTPIN (-125 50) $PN 2
J 0
(-160 60);
DISPLAY 0.617021 (-160 60);
PAINT AQUA (-160 60);
FORCEPROP 1 LAST PACK_TYPE SM
J 0
(-237 -42);
DISPLAY 0.702128 (-237 -42);
PAINT SKYBLUE (-237 -42);
DISPLAY INVISIBLE (-237 -42);
FORCEPROP 1 LAST PART_NUMBER D95126-001
J 0
(-200 100);
DISPLAY 0.872340 (-200 100);
PAINT BLUE (-200 100);
DISPLAY INVISIBLE (-200 100);
FORCEPROP 2 LAST ROOM LBG
J 0
(-200 200);
DISPLAY 1.021277 (-200 200);
PAINT ORANGE (-200 200);
DISPLAY INVISIBLE (-200 200);
FORCEPROP 1 LAST PATH I19
J 0
(-200 150);
DISPLAY 0.872340 (-200 150);
PAINT PINK (-200 150);
DISPLAY INVISIBLE (-200 150);
FORCEPROP 2 LAST CDS_LOCATION Y9F1
J 1
(-220 149);
DISPLAY 0.617021 (-220 149);
PAINT AQUA (-220 149);
DISPLAY INVISIBLE (-220 149);
FORCEPROP 2 LAST SEC 1
J 0
(-200 200);
DISPLAY 0.680851 (-200 200);
PAINT MONO (-200 200);
DISPLAY INVISIBLE (-200 200);
FORCEPROP 2 LAST SEC_TYPE SM
J 0
(-200 200);
DISPLAY 1.021277 (-200 200);
PAINT ORANGE (-200 200);
DISPLAY INVISIBLE (-200 200);
FORCEPROP 2 LAST CDS_LIB mstr_discrete
J 0
(-225 50);
PAINT MONO (-225 50);
DISPLAY INVISIBLE (-225 50);
FORCEPROP 2 LAST BOM_COST LBG_UART
J 0
(-200 250);
DISPLAY 1.021277 (-200 250);
PAINT ORANGE (-200 250);
DISPLAY INVISIBLE (-200 250);
FORCEADD OFFPAGE..1
(-225 725);
FORCEPROP 2 LAST $XR0 138 
J 0
(-477 725);
DISPLAY 0.638298 (-477 725);
PAINT MONO (-477 725);
FORCEPROP 2 LAST $XR1 108 
J 0
(-597 725);
DISPLAY 0.638298 (-597 725);
PAINT MONO (-597 725);
FORCEPROP 2 LAST $XR2 190 
J 0
(-717 725);
DISPLAY 0.638298 (-717 725);
PAINT MONO (-717 725);
FORCEPROP 2 LAST CDS_LIB mstr_standard
J 0
(-225 725);
PAINT MONO (-225 725);
DISPLAY INVISIBLE (-225 725);
FORCEPROP 1 LAST COMMENT_BODY TRUE
J 0
(-100 625);
DISPLAY 0.872340 (-100 625);
PAINT GREEN (-100 625);
DISPLAY INVISIBLE (-100 625);
FORCEPROP 2 LAST PATH I2
J 0
(-175 800);
DISPLAY 1.021277 (-175 800);
PAINT ORANGE (-175 800);
DISPLAY INVISIBLE (-175 800);
FORCEPROP 1 LAST OFFPAGE TRUE
J 0
(100 600);
DISPLAY 0.872340 (100 600);
PAINT GREEN (100 600);
DISPLAY INVISIBLE (100 600);
FORCEADD CAP..1
(-475 -200);
FORCEPROP 1 LAST MATERIAL COG
J 0
(-425 -300);
DISPLAY 0.617021 (-425 -300);
PAINT SKYBLUE (-425 -300);
FORCEPROP 1 LAST VOLTAGE 50V
J 0
(-425 -200);
DISPLAY 0.617021 (-425 -200);
PAINT SKYBLUE (-425 -200);
FORCEPROP 1 LAST TOLERANCE 5%
J 0
(-425 -250);
DISPLAY 0.617021 (-425 -250);
PAINT SKYBLUE (-425 -250);
FORCEPROP 1 LAST LOCATION C9F20
J 0
(-425 -100);
DISPLAY 0.617021 (-425 -100);
PAINT AQUA (-425 -100);
FORCEPROP 1 LAST PACK_TYPE 0402LF
J 0
(-425 -400);
DISPLAY 0.617021 (-425 -400);
PAINT SKYBLUE (-425 -400);
FORCEPROP 1 LAST VALUE 12.0PF
J 0
(-425 -150);
DISPLAY 0.617021 (-425 -150);
PAINT SKYBLUE (-425 -150);
FORCEPROP 1 LAST PART_NUMBER A36095-043
J 0
(-425 -350);
DISPLAY 0.617021 (-425 -350);
PAINT BLUE (-425 -350);
FORCEPROP 1 LASTPIN (-475 -300) $PN 2
J 0
(-465 -320);
DISPLAY 0.787234 (-465 -320);
PAINT ORANGE (-465 -320);
DISPLAY INVISIBLE (-465 -320);
FORCEPROP 2 LAST CDS_LIB mstr_discrete
J 0
(-475 -200);
PAINT ORANGE (-475 -200);
DISPLAY INVISIBLE (-475 -200);
FORCEPROP 2 LAST CDS_LOCATION C9F20
J 0
(-425 -100);
DISPLAY 0.617021 (-425 -100);
PAINT AQUA (-425 -100);
DISPLAY INVISIBLE (-425 -100);
FORCEPROP 1 LAST PATH I20
J 0
(-425 -50);
DISPLAY 0.978723 (-425 -50);
PAINT WHITE (-425 -50);
DISPLAY INVISIBLE (-425 -50);
FORCEPROP 2 LAST ROOM LBG
J 0
(-425 -50);
DISPLAY 1.021277 (-425 -50);
PAINT ORANGE (-425 -50);
DISPLAY INVISIBLE (-425 -50);
FORCEPROP 1 LASTPIN (-475 -100) $PN 1
J 0
(-465 -120);
DISPLAY 0.787234 (-465 -120);
PAINT ORANGE (-465 -120);
DISPLAY INVISIBLE (-465 -120);
FORCEPROP 2 LAST BOM_COST LBG_UART
J 0
(-425 0);
DISPLAY 1.021277 (-425 0);
PAINT ORANGE (-425 0);
DISPLAY INVISIBLE (-425 0);
FORCEPROP 2 LAST CDS_SEC 1
J 0
(-425 0);
PAINT MONO (-425 0);
DISPLAY INVISIBLE (-425 0);
FORCEPROP 2 LAST $SEC 1
J 0
(-425 0);
PAINT MONO (-425 0);
DISPLAY INVISIBLE (-425 0);
FORCEADD CAP..1
(25 -200);
FORCEPROP 1 LAST PACK_TYPE 0402LF
J 0
(75 -400);
DISPLAY 0.617021 (75 -400);
PAINT SKYBLUE (75 -400);
FORCEPROP 1 LAST MATERIAL COG
J 0
(75 -300);
DISPLAY 0.617021 (75 -300);
PAINT SKYBLUE (75 -300);
FORCEPROP 1 LAST VOLTAGE 50V
J 0
(75 -200);
DISPLAY 0.617021 (75 -200);
PAINT SKYBLUE (75 -200);
FORCEPROP 1 LAST TOLERANCE 5%
J 0
(75 -250);
DISPLAY 0.617021 (75 -250);
PAINT SKYBLUE (75 -250);
FORCEPROP 1 LAST VALUE 12.0PF
J 0
(75 -150);
DISPLAY 0.617021 (75 -150);
PAINT SKYBLUE (75 -150);
FORCEPROP 1 LAST LOCATION C9F21
J 0
(75 -100);
DISPLAY 0.617021 (75 -100);
PAINT AQUA (75 -100);
FORCEPROP 1 LAST PART_NUMBER A36095-043
J 0
(75 -350);
DISPLAY 0.617021 (75 -350);
PAINT BLUE (75 -350);
FORCEPROP 1 LASTPIN (25 -300) $PN 2
J 0
(35 -320);
DISPLAY 0.787234 (35 -320);
PAINT ORANGE (35 -320);
DISPLAY INVISIBLE (35 -320);
FORCEPROP 2 LAST CDS_LIB mstr_discrete
J 0
(25 -200);
PAINT ORANGE (25 -200);
DISPLAY INVISIBLE (25 -200);
FORCEPROP 2 LAST CDS_LOCATION C9F21
J 0
(75 -100);
DISPLAY 0.617021 (75 -100);
PAINT AQUA (75 -100);
DISPLAY INVISIBLE (75 -100);
FORCEPROP 1 LAST PATH I21
J 0
(75 -50);
DISPLAY 0.978723 (75 -50);
PAINT WHITE (75 -50);
DISPLAY INVISIBLE (75 -50);
FORCEPROP 2 LAST ROOM LBG
J 0
(75 -50);
DISPLAY 1.021277 (75 -50);
PAINT ORANGE (75 -50);
DISPLAY INVISIBLE (75 -50);
FORCEPROP 1 LASTPIN (25 -100) $PN 1
J 0
(35 -120);
DISPLAY 0.787234 (35 -120);
PAINT ORANGE (35 -120);
DISPLAY INVISIBLE (35 -120);
FORCEPROP 2 LAST BOM_COST LBG_UART
J 0
(75 0);
DISPLAY 1.021277 (75 0);
PAINT ORANGE (75 0);
DISPLAY INVISIBLE (75 0);
FORCEPROP 2 LAST CDS_SEC 1
J 0
(75 0);
PAINT MONO (75 0);
DISPLAY INVISIBLE (75 0);
FORCEPROP 2 LAST $SEC 1
J 0
(75 0);
PAINT MONO (75 0);
DISPLAY INVISIBLE (75 0);
FORCEADD GND..1
(25 -425);
FORCEPROP 3 LASTPIN (25 -375) SIG_NAME GND\g
J 0
(35 -365);
DISPLAY 0.659574 (35 -365);
PAINT MONO (35 -365);
DISPLAY INVISIBLE (35 -365);
FORCEPROP 1 LAST BODY_TYPE PLUMBING
J 0
(-20 -468);
DISPLAY 0.340426 (-20 -468);
PAINT GREEN (-20 -468);
DISPLAY INVISIBLE (-20 -468);
FORCEPROP 1 LAST VOLTAGE 0.0V
J 0
(-20 -468);
DISPLAY 0.340426 (-20 -468);
PAINT SKYBLUE (-20 -468);
DISPLAY INVISIBLE (-20 -468);
FORCEPROP 2 LAST CDS_LIB mstr_symbols
J 0
(25 -425);
PAINT MONO (25 -425);
DISPLAY INVISIBLE (25 -425);
FORCEPROP 1 LAST SIZE 1B
J 0
(100 -475);
DISPLAY 0.872340 (100 -475);
PAINT AQUA (100 -475);
DISPLAY INVISIBLE (100 -475);
FORCEPROP 1 LAST PATH I22
J 0
(100 -425);
DISPLAY 0.872340 (100 -425);
PAINT AQUA (100 -425);
DISPLAY INVISIBLE (100 -425);
FORCEPROP 1 LAST HDL_POWER GND
J 0
(25 -275);
DISPLAY 0.872340 (25 -275);
PAINT GREEN (25 -275);
DISPLAY INVISIBLE (25 -275);
FORCEADD GND..1
(-475 -425);
FORCEPROP 3 LASTPIN (-475 -375) SIG_NAME GND\g
J 0
(-465 -365);
DISPLAY 0.659574 (-465 -365);
PAINT MONO (-465 -365);
DISPLAY INVISIBLE (-465 -365);
FORCEPROP 1 LAST BODY_TYPE PLUMBING
J 0
(-520 -468);
DISPLAY 0.340426 (-520 -468);
PAINT GREEN (-520 -468);
DISPLAY INVISIBLE (-520 -468);
FORCEPROP 1 LAST VOLTAGE 0.0V
J 0
(-520 -468);
DISPLAY 0.340426 (-520 -468);
PAINT SKYBLUE (-520 -468);
DISPLAY INVISIBLE (-520 -468);
FORCEPROP 1 LAST SIZE 1B
J 0
(-400 -475);
DISPLAY 0.872340 (-400 -475);
PAINT AQUA (-400 -475);
DISPLAY INVISIBLE (-400 -475);
FORCEPROP 2 LAST CDS_LIB mstr_symbols
J 0
(-475 -425);
PAINT MONO (-475 -425);
DISPLAY INVISIBLE (-475 -425);
FORCEPROP 1 LAST PATH I23
J 0
(-400 -425);
DISPLAY 0.872340 (-400 -425);
PAINT AQUA (-400 -425);
DISPLAY INVISIBLE (-400 -425);
FORCEPROP 1 LAST HDL_POWER GND
J 0
(-475 -275);
DISPLAY 0.872340 (-475 -275);
PAINT GREEN (-475 -275);
DISPLAY INVISIBLE (-475 -275);
FORCEADD RES..1
(125 575);
FORCEPROP 1 LAST WATTAGE 1/16W
J 2
(25 525);
DISPLAY 0.617021 (25 525);
PAINT SKYBLUE (25 525);
FORCEPROP 1 LAST PART_NUMBER G21497-005
J 0
(-75 475);
DISPLAY 0.617021 (-75 475);
PAINT BLUE (-75 475);
FORCEPROP 1 LAST PACK_TYPE 0402
J 0
(250 475);
DISPLAY 0.617021 (250 475);
PAINT SKYBLUE (250 475);
FORCEPROP 1 LASTPIN (25 575) $PN 1
J 0
(37 587);
DISPLAY 0.617021 (37 587);
PAINT ORANGE (37 587);
FORCEPROP 1 LAST VALUE 0.0
J 2
(100 525);
DISPLAY 0.617021 (100 525);
PAINT SKYBLUE (100 525);
FORCEPROP 1 LAST LOCATION R9F58
J 0
(100 625);
DISPLAY 0.617021 (100 625);
PAINT AQUA (100 625);
FORCEPROP 1 LASTPIN (225 575) $PN 2
J 0
(187 587);
DISPLAY 0.617021 (187 587);
PAINT ORANGE (187 587);
FORCEPROP 1 LAST TOLERANCE 5%
J 0
(175 525);
DISPLAY 0.617021 (175 525);
PAINT SKYBLUE (175 525);
FORCEPROP 1 LAST MATERIAL CHIP
J 0
(250 525);
DISPLAY 0.617021 (250 525);
PAINT SKYBLUE (250 525);
FORCEPROP 2 LAST CDS_LIB mstr_discrete
J 0
(125 575);
PAINT MONO (125 575);
DISPLAY INVISIBLE (125 575);
FORCEPROP 2 LAST CDS_LOCATION R9F58
J 0
(100 625);
DISPLAY 0.617021 (100 625);
PAINT AQUA (100 625);
DISPLAY INVISIBLE (100 625);
FORCEPROP 1 LAST PATH I24
J 0
(75 725);
DISPLAY 0.978723 (75 725);
PAINT WHITE (75 725);
DISPLAY INVISIBLE (75 725);
FORCEPROP 2 LAST BOM_COST LBG_UART
J 0
(175 700);
DISPLAY 1.021277 (175 700);
PAINT ORANGE (175 700);
DISPLAY INVISIBLE (175 700);
FORCEPROP 2 LAST ROOM LBG
J 0
(175 650);
DISPLAY 1.021277 (175 650);
PAINT ORANGE (175 650);
DISPLAY INVISIBLE (175 650);
FORCEPROP 2 LAST SEC_TYPE 0402
J 0
(75 775);
DISPLAY 1.021277 (75 775);
PAINT ORANGE (75 775);
DISPLAY INVISIBLE (75 775);
FORCEPROP 2 LAST SEC 1
J 0
(75 775);
PAINT MONO (75 775);
DISPLAY INVISIBLE (75 775);
FORCEADD RES..1
(275 325);
FORCEPROP 1 LASTPIN (175 325) $PN 1
J 0
(187 337);
DISPLAY 0.617021 (187 337);
PAINT ORANGE (187 337);
FORCEPROP 1 LAST WATTAGE 1/16W
J 2
(175 275);
DISPLAY 0.617021 (175 275);
PAINT SKYBLUE (175 275);
FORCEPROP 1 LAST VALUE 0.0
J 2
(250 275);
DISPLAY 0.617021 (250 275);
PAINT SKYBLUE (250 275);
FORCEPROP 1 LAST LOCATION R9F59
J 0
(225 375);
DISPLAY 0.617021 (225 375);
PAINT AQUA (225 375);
FORCEPROP 1 LAST PART_NUMBER G21497-005
J 0
(75 225);
DISPLAY 0.617021 (75 225);
PAINT BLUE (75 225);
FORCEPROP 1 LASTPIN (375 325) $PN 2
J 0
(337 337);
DISPLAY 0.617021 (337 337);
PAINT ORANGE (337 337);
FORCEPROP 1 LAST TOLERANCE 5%
J 0
(325 275);
DISPLAY 0.617021 (325 275);
PAINT SKYBLUE (325 275);
FORCEPROP 1 LAST MATERIAL CHIP
J 0
(400 275);
DISPLAY 0.617021 (400 275);
PAINT SKYBLUE (400 275);
FORCEPROP 1 LAST PACK_TYPE 0402
J 0
(400 225);
DISPLAY 0.617021 (400 225);
PAINT SKYBLUE (400 225);
FORCEPROP 2 LAST ROOM LBG
J 0
(200 400);
DISPLAY 1.021277 (200 400);
PAINT ORANGE (200 400);
DISPLAY INVISIBLE (200 400);
FORCEPROP 2 LAST CDS_LOCATION R9F59
J 0
(225 375);
DISPLAY 0.617021 (225 375);
PAINT AQUA (225 375);
DISPLAY INVISIBLE (225 375);
FORCEPROP 2 LAST BOM_COST LBG_UART
J 0
(200 450);
DISPLAY 1.021277 (200 450);
PAINT ORANGE (200 450);
DISPLAY INVISIBLE (200 450);
FORCEPROP 2 LAST CDS_LIB mstr_discrete
J 0
(275 325);
PAINT MONO (275 325);
DISPLAY INVISIBLE (275 325);
FORCEPROP 1 LAST PATH I25
J 0
(225 475);
DISPLAY 0.978723 (225 475);
PAINT WHITE (225 475);
DISPLAY INVISIBLE (225 475);
FORCEPROP 2 LAST SEC 1
J 0
(225 525);
PAINT MONO (225 525);
DISPLAY INVISIBLE (225 525);
FORCEPROP 2 LAST SEC_TYPE 0402
J 0
(225 525);
DISPLAY 1.021277 (225 525);
PAINT ORANGE (225 525);
DISPLAY INVISIBLE (225 525);
FORCEADD OFFPAGE..6
(-225 675);
FORCEPROP 2 LAST $XR0 108 
J 0
(-505 675);
DISPLAY 0.638298 (-505 675);
PAINT MONO (-505 675);
FORCEPROP 2 LAST $XR1 138 
J 0
(-625 675);
DISPLAY 0.638298 (-625 675);
PAINT MONO (-625 675);
FORCEPROP 2 LAST $XR2 190 
J 0
(-745 675);
DISPLAY 0.638298 (-745 675);
PAINT MONO (-745 675);
FORCEPROP 2 LAST CDS_LIB mstr_standard
J 0
(-225 675);
PAINT MONO (-225 675);
DISPLAY INVISIBLE (-225 675);
FORCEPROP 1 LAST COMMENT_BODY TRUE
J 0
(-125 600);
DISPLAY 0.872340 (-125 600);
PAINT GREEN (-125 600);
DISPLAY INVISIBLE (-125 600);
FORCEPROP 2 LAST PATH I3
J 0
(-175 750);
DISPLAY 1.021277 (-175 750);
PAINT ORANGE (-175 750);
DISPLAY INVISIBLE (-175 750);
FORCEPROP 1 LAST OFFPAGE TRUE
J 0
(100 550);
DISPLAY 0.872340 (100 550);
PAINT GREEN (100 550);
DISPLAY INVISIBLE (100 550);
FORCEADD RES..2
(3700 700);
FORCEPROP 1 LASTPIN (3700 600) $PN 2
J 0
(3705 610);
DISPLAY 0.617021 (3705 610);
PAINT ORANGE (3705 610);
FORCEPROP 1 LAST TOLERANCE 1%
J 0
(3745 725);
DISPLAY 0.617021 (3745 725);
PAINT SKYBLUE (3745 725);
FORCEPROP 1 LASTPIN (3700 800) $PN 1
J 0
(3705 762);
DISPLAY 0.617021 (3705 762);
PAINT ORANGE (3705 762);
FORCEPROP 1 LAST WATTAGE 1/16W
J 0
(3740 675);
DISPLAY 0.617021 (3740 675);
PAINT SKYBLUE (3740 675);
FORCEPROP 1 LAST MATERIAL CHIP
J 0
(3740 625);
DISPLAY 0.617021 (3740 625);
PAINT SKYBLUE (3740 625);
FORCEPROP 1 LAST PACK_TYPE 0402
J 0
(3740 525);
DISPLAY 0.617021 (3740 525);
PAINT SKYBLUE (3740 525);
FORCEPROP 1 LAST VALUE 4.75K
J 0
(3745 775);
DISPLAY 0.617021 (3745 775);
PAINT SKYBLUE (3745 775);
FORCEPROP 1 LAST PART_NUMBER G21796-072
J 0
(3740 575);
DISPLAY 0.617021 (3740 575);
PAINT BLUE (3740 575);
FORCEPROP 1 LAST LOCATION R9F55
J 0
(3745 825);
DISPLAY 0.617021 (3745 825);
PAINT AQUA (3745 825);
FORCEPROP 2 LAST CDS_LIB mstr_discrete
J 0
(3700 700);
PAINT MONO (3700 700);
DISPLAY INVISIBLE (3700 700);
FORCEPROP 2 LAST ROOM LBG
J 0
(3650 850);
DISPLAY 1.021277 (3650 850);
PAINT ORANGE (3650 850);
DISPLAY INVISIBLE (3650 850);
FORCEPROP 2 LAST BOM_COST LBG_UART
J 0
(3650 900);
DISPLAY 1.021277 (3650 900);
PAINT ORANGE (3650 900);
DISPLAY INVISIBLE (3650 900);
FORCEPROP 2 LAST CDS_LOCATION R9F55
J 0
(3745 825);
DISPLAY 0.617021 (3745 825);
PAINT AQUA (3745 825);
DISPLAY INVISIBLE (3745 825);
FORCEPROP 2 LAST SEC 1
J 0
(3750 925);
DISPLAY 0.680851 (3750 925);
PAINT MONO (3750 925);
DISPLAY INVISIBLE (3750 925);
FORCEPROP 2 LAST SEC_TYPE 0402
J 0
(3750 925);
DISPLAY 1.021277 (3750 925);
PAINT ORANGE (3750 925);
DISPLAY INVISIBLE (3750 925);
FORCEPROP 1 LAST PATH I30
J 0
(3750 875);
DISPLAY 0.978723 (3750 875);
PAINT WHITE (3750 875);
DISPLAY INVISIBLE (3750 875);
FORCEADD P3V3_STBY..1
(3700 900);
FORCEPROP 3 LASTPIN (3700 850) SIG_NAME P3V3_STBY\g
J 0
(3710 860);
DISPLAY 0.659574 (3710 860);
PAINT MONO (3710 860);
DISPLAY INVISIBLE (3710 860);
FORCEPROP 1 LAST HDL_POWER P3V3_STBY
J 0
(3400 775);
DISPLAY 0.872340 (3400 775);
PAINT ORANGE (3400 775);
DISPLAY INVISIBLE (3400 775);
FORCEPROP 1 LAST VOLTAGE 3.3V
J 0
(3655 857);
DISPLAY 0.340426 (3655 857);
PAINT SKYBLUE (3655 857);
DISPLAY INVISIBLE (3655 857);
FORCEPROP 1 LAST BODY_TYPE PLUMBING
J 0
(3655 857);
DISPLAY 0.340426 (3655 857);
PAINT GREEN (3655 857);
DISPLAY INVISIBLE (3655 857);
FORCEPROP 2 LAST CDS_LIB mstr_symbols
J 0
(3700 900);
PAINT MONO (3700 900);
DISPLAY INVISIBLE (3700 900);
FORCEPROP 1 LAST PATH I31
J 0
(3745 902);
DISPLAY 0.340426 (3745 902);
PAINT GREEN (3745 902);
DISPLAY INVISIBLE (3745 902);
FORCEPROP 1 LAST SIZE 1B
J 0
(3745 922);
DISPLAY 0.340426 (3745 922);
PAINT GREEN (3745 922);
DISPLAY INVISIBLE (3745 922);
FORCEADD GND..1
(675 1325);
FORCEPROP 3 LASTPIN (675 1375) SIG_NAME GND\g
J 0
(685 1385);
DISPLAY 0.659574 (685 1385);
PAINT MONO (685 1385);
DISPLAY INVISIBLE (685 1385);
FORCEPROP 1 LAST SIZE 1B
J 0
(750 1275);
DISPLAY 0.872340 (750 1275);
PAINT AQUA (750 1275);
DISPLAY INVISIBLE (750 1275);
FORCEPROP 1 LAST BODY_TYPE PLUMBING
J 0
(630 1282);
DISPLAY 0.340426 (630 1282);
PAINT GREEN (630 1282);
DISPLAY INVISIBLE (630 1282);
FORCEPROP 1 LAST VOLTAGE 0.0V
J 0
(630 1282);
DISPLAY 0.340426 (630 1282);
PAINT SKYBLUE (630 1282);
DISPLAY INVISIBLE (630 1282);
FORCEPROP 1 LAST PATH I32
J 0
(750 1325);
DISPLAY 0.872340 (750 1325);
PAINT AQUA (750 1325);
DISPLAY INVISIBLE (750 1325);
FORCEPROP 2 LAST CDS_LIB mstr_symbols
J 0
(675 1325);
PAINT MONO (675 1325);
DISPLAY INVISIBLE (675 1325);
FORCEPROP 1 LAST HDL_POWER GND
J 0
(675 1475);
DISPLAY 0.872340 (675 1475);
PAINT GREEN (675 1475);
DISPLAY INVISIBLE (675 1475);
FORCEADD RES..1
(-150 1025);
FORCEPROP 1 LAST WATTAGE 1/16W
J 2
(-275 975);
DISPLAY 0.617021 (-275 975);
PAINT SKYBLUE (-275 975);
FORCEPROP 1 LAST VALUE 4.75K
J 2
(-175 975);
DISPLAY 0.617021 (-175 975);
PAINT SKYBLUE (-175 975);
FORCEPROP 1 LAST TOLERANCE 1%
J 0
(-100 975);
DISPLAY 0.617021 (-100 975);
PAINT SKYBLUE (-100 975);
FORCEPROP 1 LASTPIN (-250 1025) $PN 1
J 0
(-238 1037);
DISPLAY 0.617021 (-238 1037);
PAINT ORANGE (-238 1037);
FORCEPROP 1 LAST LOCATION R9F47
J 0
(-200 1075);
DISPLAY 0.617021 (-200 1075);
PAINT AQUA (-200 1075);
FORCEPROP 1 LASTPIN (-50 1025) $PN 2
J 0
(-88 1037);
DISPLAY 0.617021 (-88 1037);
PAINT ORANGE (-88 1037);
FORCEPROP 1 LAST PART_NUMBER G21796-072
J 0
(-25 975);
DISPLAY 0.617021 (-25 975);
PAINT BLUE (-25 975);
FORCEPROP 1 LAST MATERIAL CHIP
J 0
(-25 975);
DISPLAY 0.617021 (-25 975);
PAINT SKYBLUE (-25 975);
DISPLAY INVISIBLE (-25 975);
FORCEPROP 2 LAST SEC_TYPE 0402
J 0
(-200 1225);
DISPLAY 1.021277 (-200 1225);
PAINT ORANGE (-200 1225);
DISPLAY INVISIBLE (-200 1225);
FORCEPROP 1 LAST PATH I4
J 0
(-200 1175);
DISPLAY 0.978723 (-200 1175);
PAINT WHITE (-200 1175);
DISPLAY INVISIBLE (-200 1175);
FORCEPROP 2 LAST CDS_LOCATION R9F47
J 0
(-200 1075);
DISPLAY 0.617021 (-200 1075);
PAINT AQUA (-200 1075);
DISPLAY INVISIBLE (-200 1075);
FORCEPROP 2 LAST SEC 1
J 0
(-200 1225);
PAINT MONO (-200 1225);
DISPLAY INVISIBLE (-200 1225);
FORCEPROP 2 LAST CDS_LIB mstr_discrete
J 0
(-150 1025);
PAINT MONO (-150 1025);
DISPLAY INVISIBLE (-150 1025);
FORCEPROP 2 LAST BOM_COST LBG_UART
J 0
(-25 1075);
DISPLAY 1.021277 (-25 1075);
PAINT ORANGE (-25 1075);
DISPLAY INVISIBLE (-25 1075);
FORCEPROP 2 LAST ROOM LBG
J 0
(-25 1025);
DISPLAY 1.021277 (-25 1025);
PAINT ORANGE (-25 1025);
DISPLAY INVISIBLE (-25 1025);
FORCEPROP 1 LAST PACK_TYPE 0402
J 0
(75 975);
DISPLAY 0.617021 (75 975);
PAINT SKYBLUE (75 975);
DISPLAY INVISIBLE (75 975);
FORCEADD RES..1
(3950 1225);
FORCEPROP 1 LAST VALUE 0.0
J 2
(3925 1175);
DISPLAY 0.617021 (3925 1175);
PAINT SKYBLUE (3925 1175);
FORCEPROP 1 LAST LOCATION R9F57
J 0
(3750 1225);
DISPLAY 0.617021 (3750 1225);
PAINT AQUA (3750 1225);
FORCEPROP 1 LAST WATTAGE 1/16W
J 2
(3850 1175);
DISPLAY 0.617021 (3850 1175);
PAINT SKYBLUE (3850 1175);
FORCEPROP 1 LASTPIN (3850 1225) $PN 1
J 0
(3862 1237);
DISPLAY 0.617021 (3862 1237);
PAINT ORANGE (3862 1237);
FORCEPROP 1 LAST TOLERANCE 5%
J 0
(4000 1175);
DISPLAY 0.617021 (4000 1175);
PAINT SKYBLUE (4000 1175);
FORCEPROP 1 LASTPIN (4050 1225) $PN 2
J 0
(4012 1237);
DISPLAY 0.617021 (4012 1237);
PAINT ORANGE (4012 1237);
FORCEPROP 1 LAST MATERIAL CHIP
J 0
(4075 1175);
DISPLAY 0.617021 (4075 1175);
PAINT SKYBLUE (4075 1175);
FORCEPROP 1 LAST PART_NUMBER G21497-005
J 0
(4075 1225);
DISPLAY 0.617021 (4075 1225);
PAINT BLUE (4075 1225);
FORCEPROP 1 LAST PACK_TYPE 0402
J 0
(4175 1175);
DISPLAY 0.617021 (4175 1175);
PAINT SKYBLUE (4175 1175);
FORCEPROP 2 LAST CDS_LOCATION R9F57
J 0
(3750 1225);
DISPLAY 0.617021 (3750 1225);
PAINT AQUA (3750 1225);
DISPLAY INVISIBLE (3750 1225);
FORCEPROP 2 LAST CDS_LIB mstr_discrete
J 0
(3950 1225);
PAINT MONO (3950 1225);
DISPLAY INVISIBLE (3950 1225);
FORCEPROP 1 LAST PATH I48
J 0
(3900 1375);
DISPLAY 0.978723 (3900 1375);
PAINT WHITE (3900 1375);
DISPLAY INVISIBLE (3900 1375);
FORCEPROP 2 LAST ROOM LBG
J 0
(4000 1300);
DISPLAY 1.021277 (4000 1300);
PAINT ORANGE (4000 1300);
DISPLAY INVISIBLE (4000 1300);
FORCEPROP 2 LAST SEC 1
J 0
(3900 1425);
PAINT MONO (3900 1425);
DISPLAY INVISIBLE (3900 1425);
FORCEPROP 2 LAST BOM_COST LBG_UART
J 0
(4000 1350);
DISPLAY 1.021277 (4000 1350);
PAINT ORANGE (4000 1350);
DISPLAY INVISIBLE (4000 1350);
FORCEPROP 2 LAST SEC_TYPE 0402
J 0
(3900 1425);
DISPLAY 1.021277 (3900 1425);
PAINT ORANGE (3900 1425);
DISPLAY INVISIBLE (3900 1425);
FORCEADD RES..1
(3475 1275);
FORCEPROP 1 LAST WATTAGE 1/16W
J 2
(3375 1225);
DISPLAY 0.617021 (3375 1225);
PAINT SKYBLUE (3375 1225);
FORCEPROP 1 LAST LOCATION R9F56
J 0
(3275 1275);
DISPLAY 0.617021 (3275 1275);
PAINT AQUA (3275 1275);
FORCEPROP 1 LAST TOLERANCE 5%
J 0
(3525 1225);
DISPLAY 0.617021 (3525 1225);
PAINT SKYBLUE (3525 1225);
FORCEPROP 1 LAST VALUE 0.0
J 2
(3450 1225);
DISPLAY 0.617021 (3450 1225);
PAINT SKYBLUE (3450 1225);
FORCEPROP 1 LASTPIN (3575 1275) $PN 2
J 0
(3537 1287);
DISPLAY 0.617021 (3537 1287);
PAINT ORANGE (3537 1287);
FORCEPROP 1 LASTPIN (3375 1275) $PN 1
J 0
(3387 1287);
DISPLAY 0.617021 (3387 1287);
PAINT ORANGE (3387 1287);
FORCEPROP 1 LAST MATERIAL CHIP
J 0
(3600 1225);
DISPLAY 0.617021 (3600 1225);
PAINT SKYBLUE (3600 1225);
FORCEPROP 1 LAST PACK_TYPE 0402
J 0
(3700 1225);
DISPLAY 0.617021 (3700 1225);
PAINT SKYBLUE (3700 1225);
FORCEPROP 1 LAST PART_NUMBER G21497-005
J 0
(3600 1275);
DISPLAY 0.617021 (3600 1275);
PAINT BLUE (3600 1275);
FORCEPROP 2 LAST CDS_LOCATION R9F56
J 0
(3275 1275);
DISPLAY 0.617021 (3275 1275);
PAINT AQUA (3275 1275);
DISPLAY INVISIBLE (3275 1275);
FORCEPROP 2 LAST CDS_LIB mstr_discrete
J 0
(3475 1275);
PAINT MONO (3475 1275);
DISPLAY INVISIBLE (3475 1275);
FORCEPROP 2 LAST ROOM LBG
J 0
(3525 1350);
DISPLAY 1.021277 (3525 1350);
PAINT ORANGE (3525 1350);
DISPLAY INVISIBLE (3525 1350);
FORCEPROP 1 LAST PATH I49
J 0
(3425 1425);
DISPLAY 0.978723 (3425 1425);
PAINT WHITE (3425 1425);
DISPLAY INVISIBLE (3425 1425);
FORCEPROP 2 LAST SEC 1
J 0
(3425 1475);
PAINT MONO (3425 1475);
DISPLAY INVISIBLE (3425 1475);
FORCEPROP 2 LAST BOM_COST LBG_UART
J 0
(3525 1400);
DISPLAY 1.021277 (3525 1400);
PAINT ORANGE (3525 1400);
DISPLAY INVISIBLE (3525 1400);
FORCEPROP 2 LAST SEC_TYPE 0402
J 0
(3425 1475);
DISPLAY 1.021277 (3425 1475);
PAINT ORANGE (3425 1475);
DISPLAY INVISIBLE (3425 1475);
FORCEADD P3V3_STBY..1
(-475 1150);
FORCEPROP 3 LASTPIN (-475 1100) SIG_NAME P3V3_STBY\g
J 0
(-465 1110);
DISPLAY 0.659574 (-465 1110);
PAINT MONO (-465 1110);
DISPLAY INVISIBLE (-465 1110);
FORCEPROP 1 LAST HDL_POWER P3V3_STBY
J 0
(-775 1025);
DISPLAY 0.872340 (-775 1025);
PAINT ORANGE (-775 1025);
DISPLAY INVISIBLE (-775 1025);
FORCEPROP 1 LAST BODY_TYPE PLUMBING
J 0
(-520 1107);
DISPLAY 0.340426 (-520 1107);
PAINT GREEN (-520 1107);
DISPLAY INVISIBLE (-520 1107);
FORCEPROP 1 LAST VOLTAGE 3.3V
J 0
(-520 1107);
DISPLAY 0.340426 (-520 1107);
PAINT SKYBLUE (-520 1107);
DISPLAY INVISIBLE (-520 1107);
FORCEPROP 2 LAST CDS_LIB mstr_symbols
J 0
(-475 1150);
PAINT MONO (-475 1150);
DISPLAY INVISIBLE (-475 1150);
FORCEPROP 1 LAST SIZE 1B
J 0
(-430 1172);
DISPLAY 0.340426 (-430 1172);
PAINT GREEN (-430 1172);
DISPLAY INVISIBLE (-430 1172);
FORCEPROP 1 LAST PATH I5
J 0
(-430 1152);
DISPLAY 0.340426 (-430 1152);
PAINT GREEN (-430 1152);
DISPLAY INVISIBLE (-430 1152);
FORCEADD OFFPAGE..2
(4950 1275);
FORCEPROP 2 LAST $XR0 145 
J 0
(5139 1275);
DISPLAY 0.638298 (5139 1275);
PAINT MONO (5139 1275);
FORCEPROP 2 LAST $XR1 190 
J 0
(5259 1275);
DISPLAY 0.638298 (5259 1275);
PAINT MONO (5259 1275);
FORCEPROP 2 LAST $XR2 158 
J 0
(5379 1275);
DISPLAY 0.638298 (5379 1275);
PAINT MONO (5379 1275);
FORCEPROP 1 LAST COMMENT_BODY TRUE
J 0
(4905 1180);
DISPLAY 0.872340 (4905 1180);
PAINT GREEN (4905 1180);
DISPLAY INVISIBLE (4905 1180);
FORCEPROP 2 LAST CDS_LIB mstr_standard
J 0
(4950 1275);
PAINT ORANGE (4950 1275);
DISPLAY INVISIBLE (4950 1275);
FORCEPROP 2 LAST PATH I50
J 0
(5000 1350);
DISPLAY 1.021277 (5000 1350);
PAINT ORANGE (5000 1350);
DISPLAY INVISIBLE (5000 1350);
FORCEPROP 1 LAST OFFPAGE TRUE
J 0
(5275 1150);
DISPLAY 0.872340 (5275 1150);
PAINT GREEN (5275 1150);
DISPLAY INVISIBLE (5275 1150);
FORCEADD OFFPAGE..2
(4950 1225);
FORCEPROP 2 LAST $XR0 145 
J 0
(5139 1225);
DISPLAY 0.638298 (5139 1225);
PAINT MONO (5139 1225);
FORCEPROP 2 LAST $XR1 151 
J 0
(5259 1225);
DISPLAY 0.638298 (5259 1225);
PAINT MONO (5259 1225);
FORCEPROP 2 LAST $XR2 190 
J 0
(5379 1225);
DISPLAY 0.638298 (5379 1225);
PAINT MONO (5379 1225);
FORCEPROP 2 LAST $XR3 158 
J 0
(5379 1225);
DISPLAY 0.638298 (5379 1225);
PAINT MONO (5379 1225);
FORCEPROP 2 LAST CDS_LIB mstr_standard
J 0
(4950 1225);
PAINT ORANGE (4950 1225);
DISPLAY INVISIBLE (4950 1225);
FORCEPROP 1 LAST COMMENT_BODY TRUE
J 0
(4905 1130);
DISPLAY 0.872340 (4905 1130);
PAINT GREEN (4905 1130);
DISPLAY INVISIBLE (4905 1130);
FORCEPROP 1 LAST OFFPAGE TRUE
J 0
(5275 1100);
DISPLAY 0.872340 (5275 1100);
PAINT GREEN (5275 1100);
DISPLAY INVISIBLE (5275 1100);
FORCEPROP 2 LAST PATH I51
J 0
(5125 1300);
DISPLAY 1.021277 (5125 1300);
PAINT ORANGE (5125 1300);
DISPLAY INVISIBLE (5125 1300);
FORCEADD RES..1
(-750 1500);
FORCEPROP 1 LAST WATTAGE 1/16W
J 2
(-850 1450);
DISPLAY 0.617021 (-850 1450);
PAINT SKYBLUE (-850 1450);
FORCEPROP 1 LAST LOCATION R9F54
J 0
(-950 1500);
DISPLAY 0.617021 (-950 1500);
PAINT AQUA (-950 1500);
FORCEPROP 1 LAST VALUE 0.0
J 2
(-775 1450);
DISPLAY 0.617021 (-775 1450);
PAINT SKYBLUE (-775 1450);
FORCEPROP 1 LAST TOLERANCE 5%
J 0
(-700 1450);
DISPLAY 0.617021 (-700 1450);
PAINT SKYBLUE (-700 1450);
FORCEPROP 1 LASTPIN (-650 1500) $PN 2
J 0
(-688 1512);
DISPLAY 0.617021 (-688 1512);
PAINT ORANGE (-688 1512);
FORCEPROP 1 LASTPIN (-850 1500) $PN 1
J 0
(-838 1512);
DISPLAY 0.617021 (-838 1512);
PAINT ORANGE (-838 1512);
FORCEPROP 1 LAST MATERIAL CHIP
J 0
(-625 1450);
DISPLAY 0.617021 (-625 1450);
PAINT SKYBLUE (-625 1450);
FORCEPROP 1 LAST PACK_TYPE 0402
J 0
(-525 1450);
DISPLAY 0.617021 (-525 1450);
PAINT SKYBLUE (-525 1450);
FORCEPROP 1 LAST PART_NUMBER G21497-005
J 0
(-625 1500);
DISPLAY 0.617021 (-625 1500);
PAINT BLUE (-625 1500);
FORCEPROP 2 LAST CDS_LOCATION R9F54
J 0
(-950 1500);
DISPLAY 0.617021 (-950 1500);
PAINT AQUA (-950 1500);
DISPLAY INVISIBLE (-950 1500);
FORCEPROP 2 LAST CDS_LIB mstr_discrete
J 0
(-750 1500);
PAINT MONO (-750 1500);
DISPLAY INVISIBLE (-750 1500);
FORCEPROP 2 LAST ROOM LBG
J 0
(-700 1575);
DISPLAY 1.021277 (-700 1575);
PAINT ORANGE (-700 1575);
DISPLAY INVISIBLE (-700 1575);
FORCEPROP 2 LAST BOM_COST LBG_UART
J 0
(-700 1625);
DISPLAY 1.021277 (-700 1625);
PAINT ORANGE (-700 1625);
DISPLAY INVISIBLE (-700 1625);
FORCEPROP 2 LAST SEC 1
J 0
(-800 1700);
PAINT MONO (-800 1700);
DISPLAY INVISIBLE (-800 1700);
FORCEPROP 1 LAST PATH I52
J 0
(-800 1650);
DISPLAY 0.978723 (-800 1650);
PAINT WHITE (-800 1650);
DISPLAY INVISIBLE (-800 1650);
FORCEPROP 2 LAST SEC_TYPE 0402
J 0
(-800 1700);
DISPLAY 1.021277 (-800 1700);
PAINT ORANGE (-800 1700);
DISPLAY INVISIBLE (-800 1700);
FORCEADD RES..1
(-275 1450);
FORCEPROP 1 LAST WATTAGE 1/16W
J 2
(-375 1400);
DISPLAY 0.617021 (-375 1400);
PAINT SKYBLUE (-375 1400);
FORCEPROP 1 LAST PART_NUMBER G21497-005
J 0
(-525 1350);
DISPLAY 0.617021 (-525 1350);
PAINT BLUE (-525 1350);
FORCEPROP 1 LASTPIN (-375 1450) $PN 1
J 0
(-363 1462);
DISPLAY 0.617021 (-363 1462);
PAINT ORANGE (-363 1462);
FORCEPROP 1 LAST VALUE 0.0
J 2
(-300 1400);
DISPLAY 0.617021 (-300 1400);
PAINT SKYBLUE (-300 1400);
FORCEPROP 1 LAST LOCATION R9F53
J 0
(-475 1450);
DISPLAY 0.617021 (-475 1450);
PAINT AQUA (-475 1450);
FORCEPROP 1 LASTPIN (-175 1450) $PN 2
J 0
(-213 1462);
DISPLAY 0.617021 (-213 1462);
PAINT ORANGE (-213 1462);
FORCEPROP 1 LAST MATERIAL CHIP
J 0
(-250 1350);
DISPLAY 0.617021 (-250 1350);
PAINT SKYBLUE (-250 1350);
FORCEPROP 1 LAST TOLERANCE 5%
J 0
(-225 1400);
DISPLAY 0.617021 (-225 1400);
PAINT SKYBLUE (-225 1400);
FORCEPROP 1 LAST PACK_TYPE 0402
J 0
(-250 1300);
DISPLAY 0.617021 (-250 1300);
PAINT SKYBLUE (-250 1300);
FORCEPROP 2 LAST CDS_LOCATION R9F53
J 0
(-475 1450);
DISPLAY 0.617021 (-475 1450);
PAINT AQUA (-475 1450);
DISPLAY INVISIBLE (-475 1450);
FORCEPROP 2 LAST CDS_LIB mstr_discrete
J 0
(-275 1450);
PAINT MONO (-275 1450);
DISPLAY INVISIBLE (-275 1450);
FORCEPROP 2 LAST ROOM LBG
J 0
(-225 1525);
DISPLAY 1.021277 (-225 1525);
PAINT ORANGE (-225 1525);
DISPLAY INVISIBLE (-225 1525);
FORCEPROP 2 LAST SEC_TYPE 0402
J 0
(-325 1650);
DISPLAY 1.021277 (-325 1650);
PAINT ORANGE (-325 1650);
DISPLAY INVISIBLE (-325 1650);
FORCEPROP 2 LAST BOM_COST LBG_UART
J 0
(-225 1575);
DISPLAY 1.021277 (-225 1575);
PAINT ORANGE (-225 1575);
DISPLAY INVISIBLE (-225 1575);
FORCEPROP 2 LAST SEC 1
J 0
(-325 1650);
PAINT MONO (-325 1650);
DISPLAY INVISIBLE (-325 1650);
FORCEPROP 1 LAST PATH I53
J 0
(-325 1600);
DISPLAY 0.978723 (-325 1600);
PAINT WHITE (-325 1600);
DISPLAY INVISIBLE (-325 1600);
FORCEADD OFFPAGE..1
(-1800 1500);
FORCEPROP 2 LAST $XR0 158 
J 0
(-2052 1500);
DISPLAY 0.638298 (-2052 1500);
PAINT MONO (-2052 1500);
FORCEPROP 2 LAST $XR1 145 
J 0
(-2172 1500);
DISPLAY 0.638298 (-2172 1500);
PAINT MONO (-2172 1500);
FORCEPROP 2 LAST $XR2 190 
J 0
(-2052 1536);
DISPLAY 0.638298 (-2052 1536);
PAINT MONO (-2052 1536);
FORCEPROP 1 LAST COMMENT_BODY TRUE
J 0
(-1675 1400);
DISPLAY 0.872340 (-1675 1400);
PAINT GREEN (-1675 1400);
DISPLAY INVISIBLE (-1675 1400);
FORCEPROP 2 LAST CDS_LIB mstr_standard
J 0
(-1800 1500);
PAINT ORANGE (-1800 1500);
DISPLAY INVISIBLE (-1800 1500);
FORCEPROP 2 LAST PATH I54
J 0
(-1750 1575);
DISPLAY 1.021277 (-1750 1575);
PAINT ORANGE (-1750 1575);
DISPLAY INVISIBLE (-1750 1575);
FORCEPROP 1 LAST OFFPAGE TRUE
J 0
(-1475 1375);
DISPLAY 0.872340 (-1475 1375);
PAINT GREEN (-1475 1375);
DISPLAY INVISIBLE (-1475 1375);
FORCEADD OFFPAGE..1
(-1800 1450);
FORCEPROP 2 LAST $XR0 158 
J 0
(-2052 1450);
DISPLAY 0.638298 (-2052 1450);
PAINT MONO (-2052 1450);
FORCEPROP 2 LAST $XR1 145 
J 0
(-2172 1450);
DISPLAY 0.638298 (-2172 1450);
PAINT MONO (-2172 1450);
FORCEPROP 2 LAST $XR2 190 
J 0
(-2052 1414);
DISPLAY 0.638298 (-2052 1414);
PAINT MONO (-2052 1414);
FORCEPROP 2 LAST CDS_LIB mstr_standard
J 0
(-1800 1450);
PAINT ORANGE (-1800 1450);
DISPLAY INVISIBLE (-1800 1450);
FORCEPROP 1 LAST COMMENT_BODY TRUE
J 0
(-1675 1350);
DISPLAY 0.872340 (-1675 1350);
PAINT GREEN (-1675 1350);
DISPLAY INVISIBLE (-1675 1350);
FORCEPROP 2 LAST PATH I55
J 0
(-1750 1525);
DISPLAY 1.021277 (-1750 1525);
PAINT ORANGE (-1750 1525);
DISPLAY INVISIBLE (-1750 1525);
FORCEPROP 1 LAST OFFPAGE TRUE
J 0
(-1475 1325);
DISPLAY 0.872340 (-1475 1325);
PAINT GREEN (-1475 1325);
DISPLAY INVISIBLE (-1475 1325);
FORCEADD OFFPAGE..2
(5050 525);
FORCEPROP 2 LAST $XR0 190 
J 0
(5239 525);
DISPLAY 0.638298 (5239 525);
PAINT MONO (5239 525);
FORCEPROP 2 LAST $XR1 119 
J 0
(5359 525);
DISPLAY 0.638298 (5359 525);
PAINT MONO (5359 525);
FORCEPROP 2 LAST CDS_LIB mstr_standard
J 0
(5050 525);
PAINT ORANGE (5050 525);
DISPLAY INVISIBLE (5050 525);
FORCEPROP 1 LAST COMMENT_BODY TRUE
J 0
(5005 430);
DISPLAY 0.872340 (5005 430);
PAINT GREEN (5005 430);
DISPLAY INVISIBLE (5005 430);
FORCEPROP 2 LAST PATH I56
J 0
(5225 600);
DISPLAY 1.021277 (5225 600);
PAINT ORANGE (5225 600);
DISPLAY INVISIBLE (5225 600);
FORCEPROP 1 LAST OFFPAGE TRUE
J 0
(5375 400);
DISPLAY 0.872340 (5375 400);
PAINT GREEN (5375 400);
DISPLAY INVISIBLE (5375 400);
FORCEADD OFFPAGE..1
(-1800 200);
FORCEPROP 2 LAST $XR0 196 
J 0
(-2052 200);
DISPLAY 0.638298 (-2052 200);
PAINT MONO (-2052 200);
FORCEPROP 2 LAST $XR1 200 
J 0
(-2172 200);
DISPLAY 0.638298 (-2172 200);
PAINT MONO (-2172 200);
FORCEPROP 2 LAST $XR2 118 
J 0
(-2052 164);
DISPLAY 0.638298 (-2052 164);
PAINT MONO (-2052 164);
FORCEPROP 2 LAST $XR3 157 
J 0
(-2172 164);
DISPLAY 0.638298 (-2172 164);
PAINT MONO (-2172 164);
FORCEPROP 2 LAST $XR4 191 
J 0
(-2052 236);
DISPLAY 0.638298 (-2052 236);
PAINT MONO (-2052 236);
FORCEPROP 2 LASTPIN (-1750 200) SIG_NAME PWRGD_DSW_PWROK
J 0
(-1760 210);
DISPLAY 0.617021 (-1760 210);
PAINT ORANGE (-1760 210);
FORCEPROP 2 LAST CDS_LIB mstr_standard
J 0
(-1800 200);
PAINT ORANGE (-1800 200);
DISPLAY INVISIBLE (-1800 200);
FORCEPROP 1 LAST COMMENT_BODY TRUE
J 0
(-1675 100);
DISPLAY 0.872340 (-1675 100);
PAINT GREEN (-1675 100);
DISPLAY INVISIBLE (-1675 100);
FORCEPROP 2 LAST PATH I57
J 0
(-1750 275);
DISPLAY 1.021277 (-1750 275);
PAINT ORANGE (-1750 275);
DISPLAY INVISIBLE (-1750 275);
FORCEPROP 1 LAST OFFPAGE TRUE
J 0
(-1475 75);
DISPLAY 0.872340 (-1475 75);
PAINT GREEN (-1475 75);
DISPLAY INVISIBLE (-1475 75);
FORCEADD P3V3_STBY..1
(550 2050);
FORCEPROP 3 LASTPIN (550 2000) SIG_NAME P3V3_STBY\g
J 0
(560 2010);
DISPLAY 0.659574 (560 2010);
PAINT MONO (560 2010);
DISPLAY INVISIBLE (560 2010);
FORCEPROP 1 LAST HDL_POWER P3V3_STBY
J 0
(250 1925);
DISPLAY 0.872340 (250 1925);
PAINT ORANGE (250 1925);
DISPLAY INVISIBLE (250 1925);
FORCEPROP 1 LAST BODY_TYPE PLUMBING
J 0
(505 2007);
DISPLAY 0.340426 (505 2007);
PAINT GREEN (505 2007);
DISPLAY INVISIBLE (505 2007);
FORCEPROP 1 LAST VOLTAGE 3.3V
J 0
(505 2007);
DISPLAY 0.340426 (505 2007);
PAINT SKYBLUE (505 2007);
DISPLAY INVISIBLE (505 2007);
FORCEPROP 1 LAST SIZE 1B
J 0
(595 2072);
DISPLAY 0.340426 (595 2072);
PAINT GREEN (595 2072);
DISPLAY INVISIBLE (595 2072);
FORCEPROP 2 LAST CDS_LIB mstr_symbols
J 0
(550 2050);
PAINT MONO (550 2050);
DISPLAY INVISIBLE (550 2050);
FORCEPROP 1 LAST PATH I6
J 0
(595 2052);
DISPLAY 0.340426 (595 2052);
PAINT GREEN (595 2052);
DISPLAY INVISIBLE (595 2052);
FORCEADD CAP_A..1
(325 1775);
FORCEPROP 1 LASTPIN (325 1675) $PN 2
J 0
(335 1655);
DISPLAY 0.617021 (335 1655);
PAINT ORANGE (335 1655);
FORCEPROP 1 LAST MATERIAL X7R
J 0
(375 1675);
DISPLAY 0.617021 (375 1675);
PAINT SKYBLUE (375 1675);
FORCEPROP 1 LAST TOLERANCE 10%
J 0
(375 1725);
DISPLAY 0.617021 (375 1725);
PAINT SKYBLUE (375 1725);
FORCEPROP 1 LAST VOLTAGE 16V
J 0
(375 1775);
DISPLAY 0.617021 (375 1775);
PAINT SKYBLUE (375 1775);
FORCEPROP 1 LASTPIN (325 1875) $PN 1
J 0
(335 1855);
DISPLAY 0.617021 (335 1855);
PAINT ORANGE (335 1855);
FORCEPROP 1 LAST PACK_TYPE 0402V
J 0
(375 1575);
DISPLAY 0.617021 (375 1575);
PAINT SKYBLUE (375 1575);
FORCEPROP 1 LAST VALUE 0.1UF
J 0
(375 1825);
DISPLAY 0.617021 (375 1825);
PAINT SKYBLUE (375 1825);
FORCEPROP 1 LAST PART_NUMBER A36096-030
J 0
(375 1625);
DISPLAY 0.617021 (375 1625);
PAINT BLUE (375 1625);
FORCEPROP 1 LAST LOCATION C9F19
J 0
(375 1875);
DISPLAY 0.617021 (375 1875);
PAINT AQUA (375 1875);
FORCEPROP 2 LAST CDS_LIB dev_discrete
J 0
(325 1775);
PAINT ORANGE (325 1775);
DISPLAY INVISIBLE (325 1775);
FORCEPROP 2 LAST SEC_TYPE 0402V
J 0
(375 1975);
DISPLAY 1.021277 (375 1975);
PAINT ORANGE (375 1975);
DISPLAY INVISIBLE (375 1975);
FORCEPROP 2 LAST SEC 1
J 0
(375 1975);
PAINT MONO (375 1975);
DISPLAY INVISIBLE (375 1975);
FORCEPROP 2 LAST CDS_SEC 1
J 0
(375 1925);
PAINT ORANGE (375 1925);
DISPLAY INVISIBLE (375 1925);
FORCEPROP 2 LAST ROOM LBG
J 0
(375 1925);
DISPLAY 1.021277 (375 1925);
PAINT ORANGE (375 1925);
DISPLAY INVISIBLE (375 1925);
FORCEPROP 2 LAST CDS_LOCATION C9F19
J 0
(375 1875);
DISPLAY 0.617021 (375 1875);
PAINT AQUA (375 1875);
DISPLAY INVISIBLE (375 1875);
FORCEPROP 2 LAST BOM_COST LBG_UART
J 0
(375 1975);
DISPLAY 1.021277 (375 1975);
PAINT ORANGE (375 1975);
DISPLAY INVISIBLE (375 1975);
FORCEPROP 1 LAST PATH I7
J 0
(375 1925);
DISPLAY 0.978723 (375 1925);
PAINT WHITE (375 1925);
DISPLAY INVISIBLE (375 1925);
FORCEADD GND..1
(325 1575);
FORCEPROP 3 LASTPIN (325 1625) SIG_NAME GND\g
J 0
(335 1635);
DISPLAY 0.659574 (335 1635);
PAINT MONO (335 1635);
DISPLAY INVISIBLE (335 1635);
FORCEPROP 1 LAST SIZE 1B
J 0
(400 1525);
DISPLAY 0.872340 (400 1525);
PAINT AQUA (400 1525);
DISPLAY INVISIBLE (400 1525);
FORCEPROP 1 LAST BODY_TYPE PLUMBING
J 0
(280 1532);
DISPLAY 0.340426 (280 1532);
PAINT GREEN (280 1532);
DISPLAY INVISIBLE (280 1532);
FORCEPROP 1 LAST VOLTAGE 0.0V
J 0
(280 1532);
DISPLAY 0.340426 (280 1532);
PAINT SKYBLUE (280 1532);
DISPLAY INVISIBLE (280 1532);
FORCEPROP 2 LAST CDS_LIB mstr_symbols
J 0
(325 1575);
PAINT MONO (325 1575);
DISPLAY INVISIBLE (325 1575);
FORCEPROP 1 LAST HDL_POWER GND
J 0
(325 1725);
DISPLAY 0.872340 (325 1725);
PAINT GREEN (325 1725);
DISPLAY INVISIBLE (325 1725);
FORCEPROP 1 LAST PATH I8
J 0
(400 1575);
DISPLAY 0.872340 (400 1575);
PAINT AQUA (400 1575);
DISPLAY INVISIBLE (400 1575);
FORCEADD DESIGN_NOTE..1
(-1250 1950);
FORCEPROP 0 LAST L2 CPLD FOR UART FROM IE
J 0
(-1450 1750);
DISPLAY 0.808511 (-1450 1750);
PAINT ORANGE (-1450 1750);
FORCEPROP 0 LAST L1 UNSTUFF THESE RESISTORS WHEN USING
J 0
(-1450 1825);
DISPLAY 0.808511 (-1450 1825);
PAINT ORANGE (-1450 1825);
FORCEPROP 2 LAST CDS_LIB mstr_symbols
J 0
(-1250 1950);
PAINT ORANGE (-1250 1950);
DISPLAY INVISIBLE (-1250 1950);
FORCEPROP 1 LAST COMMENT_BODY TRUE
J 0
(-1225 2050);
DISPLAY 0.978723 (-1225 2050);
PAINT ORANGE (-1225 2050);
DISPLAY INVISIBLE (-1225 2050);
FORCEADD DNS..2
(-1495 1045);
PAINT RED (-1495 1045);
FORCEPROP 1 LAST COMMENT_BODY TRUE
R 1
J 0
(-1420 820);
DISPLAY 0.872340 (-1420 820);
PAINT GREEN (-1420 820);
DISPLAY INVISIBLE (-1420 820);
FORCEPROP 2 LAST CDS_LIB mstr_misc
J 0
(-1495 1045);
PAINT ORANGE (-1495 1045);
DISPLAY INVISIBLE (-1495 1045);
FORCEADD DESIGN_NOTE..1
(3550 1675);
FORCEPROP 0 LAST L2 CPLD FOR UART FROM IE
J 0
(3350 1475);
DISPLAY 0.808511 (3350 1475);
PAINT ORANGE (3350 1475);
FORCEPROP 0 LAST L1 UNSTUFF THESE RESISTORS WHEN USING
J 0
(3350 1550);
DISPLAY 0.808511 (3350 1550);
PAINT ORANGE (3350 1550);
FORCEPROP 2 LAST CDS_LIB mstr_symbols
J 0
(3550 1675);
PAINT ORANGE (3550 1675);
DISPLAY INVISIBLE (3550 1675);
FORCEPROP 1 LAST COMMENT_BODY TRUE
J 0
(3575 1775);
DISPLAY 0.978723 (3575 1775);
PAINT ORANGE (3575 1775);
DISPLAY INVISIBLE (3575 1775);
FORCEADD DNS..2
(-1145 1045);
PAINT RED (-1145 1045);
FORCEPROP 1 LAST COMMENT_BODY TRUE
R 1
J 0
(-1070 820);
DISPLAY 0.872340 (-1070 820);
PAINT GREEN (-1070 820);
DISPLAY INVISIBLE (-1070 820);
FORCEPROP 2 LAST CDS_LIB mstr_misc
J 0
(-1145 1045);
PAINT ORANGE (-1145 1045);
DISPLAY INVISIBLE (-1145 1045);
FORCEADD DESIGN_NOTE..1
(1075 -100);
FORCEPROP 0 LAST L1 SMBUS ADDRESS: 0X6A
J 0
(875 -225);
DISPLAY 1.021277 (875 -225);
PAINT ORANGE (875 -225);
FORCEPROP 2 LAST CDS_LIB mstr_symbols
J 0
(1075 -100);
PAINT MONO (1075 -100);
DISPLAY INVISIBLE (1075 -100);
FORCEPROP 1 LAST COMMENT_BODY TRUE
J 0
(1100 0);
DISPLAY 0.978723 (1100 0);
PAINT ORANGE (1100 0);
DISPLAY INVISIBLE (1100 0);
FORCEADD INTEL_CORP_BPAGE..1
(5800 -1575);
FORCEPROP 1 LAST CDS_CON_LAST_MODIFIED Tue Dec 01 11:52:15 2015
J 0
(4375 -1250);
DISPLAY 1.361702 (4375 -1250);
PAINT GREEN (4375 -1250);
DISPLAY INVISIBLE (4375 -1250);
FORCEPROP 1 LAST CUSTOM_TXT_CDS <CURRENT_DESIGN_SHEET> OF <TOTAL_DESIGN_SHEETS>
J 0
(5300 -1550);
PAINT GREEN (5300 -1550);
FORCEPROP 1 LAST CUSTOM_TXT_CDS <CON_LAST_MODIFIED>
J 0
(3875 -1225);
PAINT GREEN (3875 -1225);
FORCEPROP 2 LAST CUSTOM_TXT_CDS <XR_PAGE_TITLE>
J 0
(-2090 3675);
DISPLAY 0.638298 (-2090 3675);
PAINT PINK (-2090 3675);
DISPLAY INVISIBLE (-2090 3675);
FORCEPROP 1 LAST SCH_TITLE I2C/SPI TO UART BRIDGE CONTROLLER
J 0
(-2150 -1525);
DISPLAY 1.212766 (-2150 -1525);
PAINT ORANGE (-2150 -1525);
FORCEPROP 1 LAST SCH_ADDRESS1 2200 Mission College Blvd.
J 0
(1825 -1450);
DISPLAY 0.617021 (1825 -1450);
PAINT GREEN (1825 -1450);
FORCEPROP 1 LAST SCH_ADDRESS2 P.O. BOX 58119
J 0
(1825 -1500);
DISPLAY 0.617021 (1825 -1500);
PAINT GREEN (1825 -1500);
FORCEPROP 1 LAST SCH_ADDRESS3 Santa Clara, CA 95052-8119
J 0
(1825 -1550);
DISPLAY 0.617021 (1825 -1550);
PAINT GREEN (1825 -1550);
FORCEPROP 1 LAST SCH_NUMBER H4694802
J 0
(4500 -1425);
DISPLAY 1.212766 (4500 -1425);
PAINT YELLOW (4500 -1425);
FORCEPROP 1 LAST SCH_DEPT BESD
J 1
(1350 -1475);
DISPLAY 1.212766 (1350 -1475);
PAINT YELLOW (1350 -1475);
FORCEPROP 1 LAST SCH_REV 2.420
J 0
(5550 -1425);
DISPLAY 0.978723 (5550 -1425);
PAINT YELLOW (5550 -1425);
FORCEPROP 2 LAST PAGE_BORDER TRUE
J 0
(-2090 3675);
DISPLAY 0.851064 (-2090 3675);
PAINT PINK (-2090 3675);
DISPLAY INVISIBLE (-2090 3675);
FORCEPROP 2 LAST CDS_LIB mstr_symbols
J 0
(5800 -1575);
DISPLAY 1.361702 (5800 -1575);
PAINT ORANGE (5800 -1575);
DISPLAY INVISIBLE (5800 -1575);
FORCEPROP 1 LAST COMMENT_BODY TRUE
J 0
(5812 -1563);
DISPLAY 0.617021 (5812 -1563);
PAINT GREEN (5812 -1563);
DISPLAY INVISIBLE (5812 -1563);
FORCEPROP 2 LAST CDS_XR_PAGE_TITLE CR-183 : @BASEBOARD_FAB2_LIB.BASEBOARD_FAB2(SCH_1):PAGE183
J 0
(-2090 3675);
DISPLAY 0.638298 (-2090 3675);
PAINT PINK (-2090 3675);
DISPLAY INVISIBLE (-2090 3675);
WIRE 16 -1 (2250 325)(2250 375);
WIRE 16 -1 (2250 325)(2125 325);
WIRE 16 -1 (2250 75)(2250 325);
WIRE 16 -1 (2250 375)(2125 375);
WIRE 16 -1 (-1500 1150)(-1500 1250);
WIRE 16 -1 (-1150 1150)(-1150 1250);
WIRE 16 -1 (-1500 500)(-1500 375);
WIRE 16 -1 (-1150 500)(-1150 375);
WIRE 16 -1 (25 -375)(25 -300);
WIRE 16 -1 (-475 -300)(-475 -375);
WIRE 16 -1 (3700 800)(3700 850);
WIRE 16 -1 (675 1475)(825 1475);
WIRE 16 -1 (675 1425)(675 1475);
WIRE 16 -1 (675 1425)(825 1425);
WIRE 16 -1 (675 1375)(675 1425);
WIRE 16 -1 (-475 1025)(-250 1025);
WIRE 16 -1 (-475 1100)(-475 1025);
WIRE 16 -1 (550 1625)(825 1625);
WIRE 16 -1 (550 1950)(550 1625);
WIRE 16 -1 (325 1950)(550 1950);
WIRE 16 -1 (550 2000)(550 1950);
WIRE 16 -1 (325 1875)(325 1950);
WIRE 16 -1 (325 1625)(325 1675);
WIRE 16 3135 (3200 1100)(4350 1100);
WIRE 16 3135 (3200 1850)(3200 1100);
WIRE 16 3135 (4350 1100)(4350 1500);
WIRE 16 3135 (4350 1500)(4600 1500);
WIRE 16 3135 (4600 1850)(3200 1850);
WIRE 16 3135 (4600 1500)(4600 1850);
WIRE 16 -1 (5000 525)(3700 525);
FORCEPROP 0 LAST SIG_NAME FM_UART_ALERT_N
J 0
(4490 535);
DISPLAY 0.617021 (4490 535);
PAINT ORANGE (4490 535);
WIRE 16 -1 (3700 525)(3700 600);
WIRE 16 -1 (2125 525)(3700 525);
WIRE 16 -1 (4050 1225)(4900 1225);
FORCEPROP 2 LAST SIG_NAME UART_BMC_TXD5
J 2
(4900 1235);
DISPLAY 0.617021 (4900 1235);
PAINT ORANGE (4900 1235);
WIRE 16 -1 (3575 1275)(4900 1275);
FORCEPROP 2 LAST SIG_NAME SP1_BMC_HOST_UART_TX
J 2
(4900 1285);
DISPLAY 0.617021 (4900 1285);
PAINT ORANGE (4900 1285);
WIRE 16 -1 (2125 675)(3125 675);
FORCEPROP 2 LAST SIG_NAME TP_PI7C9X1172_SO
J 2
(3150 685);
DISPLAY 0.617021 (3150 685);
PAINT ORANGE (3150 685);
FORCEPROP 2 LASTPROP $XRERR UNIQUE?
J 0
(3155 675);
DISPLAY 0.638298 (3155 675);
PAINT MONO (3155 675);
DISPLAY INVISIBLE (3155 675);
WIRE 16 -1 (2125 775)(3125 775);
FORCEPROP 2 LAST SIG_NAME TP_GPIO0_DSRB_N
J 2
(3150 785);
DISPLAY 0.617021 (3150 785);
PAINT ORANGE (3150 785);
FORCEPROP 2 LASTPROP $XRERR UNIQUE?
J 0
(3155 775);
DISPLAY 0.638298 (3155 775);
PAINT MONO (3155 775);
DISPLAY INVISIBLE (3155 775);
WIRE 16 -1 (2125 825)(3125 825);
FORCEPROP 2 LAST SIG_NAME TP_GPIO1_DTRB_N
J 2
(3150 835);
DISPLAY 0.617021 (3150 835);
PAINT ORANGE (3150 835);
FORCEPROP 2 LASTPROP $XRERR UNIQUE?
J 0
(3155 825);
DISPLAY 0.638298 (3155 825);
PAINT MONO (3155 825);
DISPLAY INVISIBLE (3155 825);
WIRE 16 -1 (2125 875)(3125 875);
FORCEPROP 2 LAST SIG_NAME TP_GPIO2_CDB_N
J 2
(3150 885);
DISPLAY 0.617021 (3150 885);
PAINT ORANGE (3150 885);
FORCEPROP 2 LASTPROP $XRERR UNIQUE?
J 0
(3155 875);
DISPLAY 0.638298 (3155 875);
PAINT MONO (3155 875);
DISPLAY INVISIBLE (3155 875);
WIRE 16 -1 (2125 925)(3125 925);
FORCEPROP 2 LAST SIG_NAME TP_GPIO3_RIB_N
J 2
(3150 935);
DISPLAY 0.617021 (3150 935);
PAINT ORANGE (3150 935);
FORCEPROP 2 LASTPROP $XRERR UNIQUE?
J 0
(3155 925);
DISPLAY 0.638298 (3155 925);
PAINT MONO (3155 925);
DISPLAY INVISIBLE (3155 925);
WIRE 16 -1 (2125 975)(3125 975);
FORCEPROP 2 LAST SIG_NAME TP_GPIO4_DSRA_N
J 2
(3150 985);
DISPLAY 0.617021 (3150 985);
PAINT ORANGE (3150 985);
FORCEPROP 2 LASTPROP $XRERR UNIQUE?
J 0
(3155 975);
DISPLAY 0.638298 (3155 975);
PAINT MONO (3155 975);
DISPLAY INVISIBLE (3155 975);
WIRE 16 -1 (2125 1025)(3125 1025);
FORCEPROP 2 LAST SIG_NAME TP_GPIO5_DTRA_N
J 2
(3150 1035);
DISPLAY 0.617021 (3150 1035);
PAINT ORANGE (3150 1035);
FORCEPROP 2 LASTPROP $XRERR UNIQUE?
J 0
(3155 1025);
DISPLAY 0.638298 (3155 1025);
PAINT MONO (3155 1025);
DISPLAY INVISIBLE (3155 1025);
WIRE 16 -1 (2125 1075)(3125 1075);
FORCEPROP 2 LAST SIG_NAME TP_GPIO6_CDA_N
J 2
(3150 1085);
DISPLAY 0.617021 (3150 1085);
PAINT ORANGE (3150 1085);
FORCEPROP 2 LASTPROP $XRERR UNIQUE?
J 0
(3155 1075);
DISPLAY 0.638298 (3155 1075);
PAINT MONO (3155 1075);
DISPLAY INVISIBLE (3155 1075);
WIRE 16 -1 (2125 1125)(3125 1125);
FORCEPROP 2 LAST SIG_NAME TP_GPIO7_RIA_N
J 2
(3150 1135);
DISPLAY 0.617021 (3150 1135);
PAINT ORANGE (3150 1135);
FORCEPROP 2 LASTPROP $XRERR UNIQUE?
J 0
(3155 1125);
DISPLAY 0.638298 (3155 1125);
PAINT MONO (3155 1125);
DISPLAY INVISIBLE (3155 1125);
WIRE 16 -1 (2125 1225)(3850 1225);
FORCEPROP 2 LAST SIG_NAME UART_BRIDGE_TXD5
J 0
(2200 1235);
DISPLAY 0.617021 (2200 1235);
PAINT ORANGE (2200 1235);
FORCEPROP 2 LASTPROP $XRERR UNIQUE?
J 0
(1960 1235);
DISPLAY 0.638298 (1960 1235);
PAINT MONO (1960 1235);
DISPLAY INVISIBLE (1960 1235);
WIRE 16 -1 (3125 1625)(2125 1625);
FORCEPROP 2 LAST SIG_NAME NC_PI7C9X1172_8
J 2
(3150 1635);
DISPLAY 0.617021 (3150 1635);
PAINT ORANGE (3150 1635);
FORCEPROP 2 LASTPROP $XRERR UNIQUE?
J 0
(3155 1625);
DISPLAY 0.638298 (3155 1625);
PAINT MONO (3155 1625);
DISPLAY INVISIBLE (3155 1625);
WIRE 16 -1 (2125 1475)(3125 1475);
FORCEPROP 2 LAST SIG_NAME TP_PI7C9X1172_RTSA_N
J 2
(3150 1485);
DISPLAY 0.617021 (3150 1485);
PAINT ORANGE (3150 1485);
FORCEPROP 2 LASTPROP $XRERR UNIQUE?
J 0
(3155 1475);
DISPLAY 0.638298 (3155 1475);
PAINT MONO (3155 1475);
DISPLAY INVISIBLE (3155 1475);
WIRE 16 -1 (2125 1425)(3125 1425);
FORCEPROP 2 LAST SIG_NAME TP_PI7C9X1172_RTSB_N
J 2
(3150 1435);
DISPLAY 0.617021 (3150 1435);
PAINT ORANGE (3150 1435);
FORCEPROP 2 LASTPROP $XRERR UNIQUE?
J 0
(3155 1425);
DISPLAY 0.638298 (3155 1425);
PAINT MONO (3155 1425);
DISPLAY INVISIBLE (3155 1425);
WIRE 16 -1 (3125 1575)(2125 1575);
FORCEPROP 2 LAST SIG_NAME NC_PI7C9X1172_1
J 2
(3150 1585);
DISPLAY 0.617021 (3150 1585);
PAINT ORANGE (3150 1585);
FORCEPROP 2 LASTPROP $XRERR UNIQUE?
J 0
(3155 1575);
DISPLAY 0.638298 (3155 1575);
PAINT MONO (3155 1575);
DISPLAY INVISIBLE (3155 1575);
WIRE 16 -1 (2125 1275)(3375 1275);
FORCEPROP 2 LAST SIG_NAME SP1_HOST_BRIDGE_UART_TX
J 0
(2200 1285);
DISPLAY 0.617021 (2200 1285);
PAINT ORANGE (2200 1285);
FORCEPROP 2 LASTPROP $XRERR UNIQUE?
J 0
(1960 1285);
DISPLAY 0.638298 (1960 1285);
PAINT MONO (1960 1285);
DISPLAY INVISIBLE (1960 1285);
WIRE 16 -1 (825 1075)(150 1075);
FORCEPROP 2 LAST SIG_NAME TP_PI7C9X1172_ENIR_N
J 0
(165 1085);
DISPLAY 0.617021 (165 1085);
PAINT ORANGE (165 1085);
FORCEPROP 2 LASTPROP $XRERR UNIQUE?
J 0
(-90 1075);
DISPLAY 0.638298 (-90 1075);
PAINT MONO (-90 1075);
DISPLAY INVISIBLE (-90 1075);
WIRE 16 -1 (825 1125)(150 1125);
FORCEPROP 2 LAST SIG_NAME TP_PI7C9X1172_EN485_N
J 0
(165 1135);
DISPLAY 0.617021 (165 1135);
PAINT ORANGE (165 1135);
FORCEPROP 2 LASTPROP $XRERR UNIQUE?
J 0
(-90 1125);
DISPLAY 0.638298 (-90 1125);
PAINT MONO (-90 1125);
DISPLAY INVISIBLE (-90 1125);
WIRE 16 -1 (375 325)(825 325);
FORCEPROP 2 LAST SIG_NAME XTAL_24MHZ_OUT_R
J 0
(390 335);
DISPLAY 0.617021 (390 335);
PAINT ORANGE (390 335);
FORCEPROP 2 LASTPROP $XRERR UNIQUE?
J 0
(150 335);
DISPLAY 0.638298 (150 335);
PAINT MONO (150 335);
DISPLAY INVISIBLE (150 335);
WIRE 16 -1 (225 575)(825 575);
FORCEPROP 2 LAST SIG_NAME XTAL_24MHZ_IN_R
J 0
(415 585);
DISPLAY 0.617021 (415 585);
PAINT ORANGE (415 585);
FORCEPROP 2 LASTPROP $XRERR UNIQUE?
J 0
(175 585);
DISPLAY 0.638298 (175 585);
PAINT MONO (175 585);
DISPLAY INVISIBLE (175 585);
WIRE 16 -1 (25 325)(175 325);
WIRE 16 -1 (25 50)(25 325);
WIRE 16 -1 (25 -100)(25 50);
FORCEPROP 2 LAST SIG_NAME XTAL_24MHZ_PI7C9X1172_OUT
R 1
J 0
(15 -90);
DISPLAY 0.617021 (15 -90);
PAINT ORANGE (15 -90);
FORCEPROP 2 LASTPROP $XRERR UNIQUE?
J 0
(-225 -90);
DISPLAY 0.638298 (-225 -90);
PAINT MONO (-225 -90);
DISPLAY INVISIBLE (-225 -90);
WIRE 16 -1 (-125 50)(25 50);
WIRE 16 -1 (-850 975)(825 975);
WIRE 16 -1 (-850 200)(-850 975);
WIRE 16 -1 (-1750 200)(-850 200);
WIRE 16 -1 (-475 575)(25 575);
WIRE 16 -1 (-475 50)(-475 575);
FORCEPROP 2 LAST SIG_NAME XTAL_24MHZ_PI7C9X1172_IN
J 0
(-485 585);
DISPLAY 0.617021 (-485 585);
PAINT ORANGE (-485 585);
FORCEPROP 2 LASTPROP $XRERR UNIQUE?
J 0
(-725 585);
DISPLAY 0.638298 (-725 585);
PAINT MONO (-725 585);
DISPLAY INVISIBLE (-725 585);
WIRE 16 -1 (-475 50)(-325 50);
WIRE 16 -1 (-475 -100)(-475 50);
WIRE 16 -1 (-75 1275)(825 1275);
WIRE 16 -1 (-75 1275)(-75 1500);
FORCEPROP 2 LAST SIG_NAME SP1_HOST_BRIDGE_UART_RX
J 0
(-25 1285);
DISPLAY 0.617021 (-25 1285);
PAINT ORANGE (-25 1285);
FORCEPROP 2 LASTPROP $XRERR UNIQUE?
J 0
(-265 1285);
DISPLAY 0.638298 (-265 1285);
PAINT MONO (-265 1285);
DISPLAY INVISIBLE (-265 1285);
WIRE 16 -1 (-75 1500)(-650 1500);
WIRE 16 -1 (-125 1225)(825 1225);
FORCEPROP 2 LAST SIG_NAME UART_BRIDGE_RXD5
J 0
(-25 1235);
DISPLAY 0.617021 (-25 1235);
PAINT ORANGE (-25 1235);
FORCEPROP 2 LASTPROP $XRERR UNIQUE?
J 0
(-265 1235);
DISPLAY 0.638298 (-265 1235);
PAINT MONO (-265 1235);
DISPLAY INVISIBLE (-265 1235);
WIRE 16 -1 (-125 1225)(-125 1450);
WIRE 16 -1 (-125 1450)(-175 1450);
WIRE 16 -1 (-1150 950)(-1150 825);
WIRE 16 -1 (825 825)(-1150 825);
FORCEPROP 2 LAST SIG_NAME FM_PI7C9X1172_A1
J 0
(-485 835);
DISPLAY 0.617021 (-485 835);
PAINT ORANGE (-485 835);
FORCEPROP 2 LASTPROP $XRERR UNIQUE?
J 0
(-725 835);
DISPLAY 0.638298 (-725 835);
PAINT MONO (-725 835);
DISPLAY INVISIBLE (-725 835);
WIRE 16 -1 (-1150 700)(-1150 825);
WIRE 16 -1 (-1500 875)(825 875);
FORCEPROP 2 LAST SIG_NAME FM_PI7C9X1172_A0
J 0
(-485 885);
DISPLAY 0.617021 (-485 885);
PAINT ORANGE (-485 885);
FORCEPROP 2 LASTPROP $XRERR UNIQUE?
J 0
(-725 885);
DISPLAY 0.638298 (-725 885);
PAINT MONO (-725 885);
DISPLAY INVISIBLE (-725 885);
WIRE 16 -1 (-1500 875)(-1500 950);
WIRE 16 -1 (-1500 700)(-1500 875);
WIRE 16 -1 (-50 1025)(825 1025);
FORCEPROP 2 LAST SIG_NAME PU_PI7C9X1172_I2C_SPI_N
J 2
(750 1035);
DISPLAY 0.617021 (750 1035);
PAINT ORANGE (750 1035);
FORCEPROP 2 LASTPROP $XRERR UNIQUE?
J 0
(510 1035);
DISPLAY 0.638298 (510 1035);
PAINT MONO (510 1035);
DISPLAY INVISIBLE (510 1035);
WIRE 16 -1 (-175 675)(825 675);
FORCEPROP 2 LAST SIG_NAME SMB_SLOTX24_PCH_STBY_LVC3_SDA
J 0
(-135 685);
DISPLAY 0.617021 (-135 685);
PAINT ORANGE (-135 685);
WIRE 16 -1 (-175 725)(825 725);
FORCEPROP 2 LAST SIG_NAME SMB_SLOTX24_PCH_STBY_LVC3_SCL
J 0
(-135 735);
DISPLAY 0.617021 (-135 735);
PAINT ORANGE (-135 735);
WIRE 16 3135 (-1550 2100)(-150 2100);
WIRE 16 3135 (-1550 2100)(-1550 1675);
WIRE 16 3135 (-150 1275)(-150 2100);
WIRE 16 3135 (-975 1275)(-150 1275);
WIRE 16 3135 (-1550 1675)(-975 1675);
WIRE 16 3135 (-975 1675)(-975 1275);
WIRE 16 -1 (-1750 1450)(-375 1450);
FORCEPROP 2 LAST SIG_NAME UART_BMC_RXD5
J 0
(-1675 1460);
DISPLAY 0.617021 (-1675 1460);
PAINT ORANGE (-1675 1460);
WIRE 16 -1 (-1750 1500)(-850 1500);
FORCEPROP 2 LAST SIG_NAME SP1_BMC_HOST_UART_RX
J 0
(-1675 1510);
DISPLAY 0.617021 (-1675 1510);
PAINT ORANGE (-1675 1510);
DOT 1 (3700 525);
DOT 1 (2250 325);
DOT 1 (550 1950);
DOT 1 (675 1425);
DOT 1 (25 50);
DOT 1 (-475 50);
DOT 1 (-1150 825);
DOT 1 (-1500 875);
QUIT
